(kicad_pcb
	(version 20241229)
	(generator "pcbnew")
	(generator_version "9.0")
	(general
		(thickness 0.761)
		(legacy_teardrops no)
	)
	(paper "A4")
	(title_block
		(title " M.2 to OCuLink adapter")
		(date "2025-07-16")
		(rev "1.0.2")
		(company "Antmicro Ltd")
		(comment 1 "www.antmicro.com")
	)
	(layers
		(0 "F.Cu" signal)
		(4 "In1.Cu" signal)
		(6 "In2.Cu" signal)
		(2 "B.Cu" signal)
		(9 "F.Adhes" user "F.Adhesive")
		(11 "B.Adhes" user "B.Adhesive")
		(13 "F.Paste" user)
		(15 "B.Paste" user)
		(5 "F.SilkS" user "F.Silkscreen")
		(7 "B.SilkS" user "B.Silkscreen")
		(1 "F.Mask" user)
		(3 "B.Mask" user)
		(17 "Dwgs.User" user "User.Drawings")
		(19 "Cmts.User" user "User.Comments")
		(21 "Eco1.User" user "User.Eco1")
		(23 "Eco2.User" user "User.Eco2")
		(25 "Edge.Cuts" user)
		(27 "Margin" user)
		(31 "F.CrtYd" user "F.Courtyard")
		(29 "B.CrtYd" user "B.Courtyard")
		(35 "F.Fab" user)
		(33 "B.Fab" user)
	)
	(setup
		(stackup
			(layer "F.SilkS"
				(type "Top Silk Screen")
			)
			(layer "F.Paste"
				(type "Top Solder Paste")
			)
			(layer "F.Mask"
				(type "Top Solder Mask")
				(color "Black")
				(thickness 0.01)
			)
			(layer "F.Cu"
				(type "copper")
				(thickness 0.035)
			)
			(layer "dielectric 1"
				(type "prepreg")
				(color "FR4 natural")
				(thickness 0.1855)
				(material "7628")
				(epsilon_r 4.2)
				(loss_tangent 0)
			)
			(layer "In1.Cu"
				(type "copper")
				(thickness 0.035)
			)
			(layer "dielectric 2"
				(type "core")
				(color "FR4 natural")
				(thickness 0.23)
				(material "FR4")
				(epsilon_r 4.2)
				(loss_tangent 0.02)
			)
			(layer "In2.Cu"
				(type "copper")
				(thickness 0.035)
			)
			(layer "dielectric 3"
				(type "prepreg")
				(color "FR4 natural")
				(thickness 0.1855)
				(material "7628")
				(epsilon_r 4.2)
				(loss_tangent 0)
			)
			(layer "B.Cu"
				(type "copper")
				(thickness 0.035)
			)
			(layer "B.Mask"
				(type "Bottom Solder Mask")
				(color "Black")
				(thickness 0.01)
			)
			(layer "B.Paste"
				(type "Bottom Solder Paste")
			)
			(layer "B.SilkS"
				(type "Bottom Silk Screen")
			)
			(copper_finish "None")
			(dielectric_constraints yes)
		)
		(pad_to_mask_clearance 0)
		(allow_soldermask_bridges_in_footprints no)
		(tenting front back)
		(pcbplotparams
			(layerselection 0x00000000_00000000_55555555_5755f5ff)
			(plot_on_all_layers_selection 0x00000000_00000000_00000000_00000000)
			(disableapertmacros no)
			(usegerberextensions no)
			(usegerberattributes yes)
			(usegerberadvancedattributes yes)
			(creategerberjobfile yes)
			(dashed_line_dash_ratio 12.000000)
			(dashed_line_gap_ratio 3.000000)
			(svgprecision 4)
			(plotframeref no)
			(mode 1)
			(useauxorigin no)
			(hpglpennumber 1)
			(hpglpenspeed 20)
			(hpglpendiameter 15.000000)
			(pdf_front_fp_property_popups yes)
			(pdf_back_fp_property_popups yes)
			(pdf_metadata yes)
			(pdf_single_document no)
			(dxfpolygonmode yes)
			(dxfimperialunits yes)
			(dxfusepcbnewfont yes)
			(psnegative no)
			(psa4output no)
			(plot_black_and_white yes)
			(sketchpadsonfab no)
			(plotpadnumbers no)
			(hidednponfab no)
			(sketchdnponfab yes)
			(crossoutdnponfab yes)
			(subtractmaskfromsilk no)
			(outputformat 1)
			(mirror no)
			(drillshape 0)
			(scaleselection 1)
			(outputdirectory "Gerbers/")
		)
	)
	(net 0 "")
	(net 1 "GND")
	(net 2 "/PCIe_{x4}.TX3+")
	(net 3 "/PCIe_{x4}.TX1+")
	(net 4 "/PCIe_{x4}.RX2+")
	(net 5 "/PCIe_{x4}.TX2+")
	(net 6 "/PCIe_{x4}.RX3-")
	(net 7 "/PCIe_{x4}.RX0-")
	(net 8 "/PCIe_{x4}.TX1-")
	(net 9 "/PCIe_{x4}.RX3+")
	(net 10 "/PCIe_{x4}.TX2-")
	(net 11 "unconnected-(J1-SUSCLK-Pad68)")
	(net 12 "/PCIe_{REF0}_R.CK-")
	(net 13 "/PCIe_{REF0}_R.CK+")
	(net 14 "/PCIe_{x4}.RX2-")
	(net 15 "/PCIe_{x4}.TX0-")
	(net 16 "/PCIe_{x4}.RX1+")
	(net 17 "+3V3")
	(net 18 "unconnected-(J1-NC-Pad22)")
	(net 19 "unconnected-(J1-NC-Pad30)")
	(net 20 "unconnected-(J1-NC-Pad58)")
	(net 21 "/PCIe_{x4}.TX3-")
	(net 22 "unconnected-(J1-NC-Pad48)")
	(net 23 "/~{PERSTC}")
	(net 24 "/~{WAKEC}")
	(net 25 "/PCIe_{x4}.TX0+")
	(net 26 "/PCIe_{x4}.RX0+")
	(net 27 "/PCIe_{x4}.RX1-")
	(net 28 "unconnected-(J1-NC-Pad40)")
	(net 29 "unconnected-(J1-NC-Pad36)")
	(net 30 "unconnected-(J1-NC-Pad67)")
	(net 31 "unconnected-(J1-NC-Pad32)")
	(net 32 "unconnected-(J1-DEVSLP-Pad38)")
	(net 33 "unconnected-(J1-PEDET-Pad69)")
	(net 34 "unconnected-(J1-NC-Pad24)")
	(net 35 "unconnected-(J1-DAS-Pad10)")
	(net 36 "/PCIe_{REF0}.CK+")
	(net 37 "/~{WAKE}")
	(net 38 "/PCIe_{REF0}.CK-")
	(net 39 "unconnected-(J1-NC-Pad56)")
	(net 40 "unconnected-(J1-NC-Pad44)")
	(net 41 "Net-(J1-CLKREQ#)")
	(net 42 "unconnected-(J1-NC-Pad20)")
	(net 43 "unconnected-(J1-NC-Pad8)")
	(net 44 "unconnected-(J1-NC-Pad34)")
	(net 45 "unconnected-(J1-NC-Pad26)")
	(net 46 "unconnected-(J1-NC-Pad42)")
	(net 47 "unconnected-(J1-NC-Pad46)")
	(net 48 "unconnected-(J1-NC-Pad28)")
	(net 49 "unconnected-(J1-NC-Pad6)")
	(net 50 "Net-(J2-5V-PadA21)")
	(net 51 "/~{WAKE_C}_alt")
	(net 52 "unconnected-(J2-NC-PadA9)")
	(net 53 "unconnected-(J2-SCL-PadB9)")
	(net 54 "/~{CPRSNT}")
	(net 55 "/~{PERST}")
	(net 56 "Net-(C1-Pad2)")
	(net 57 "Net-(J2-V_{ACT}_TX_3V3)")
	(net 58 "Net-(R13-Pad1)")
	(footprint "antmicro-footprints:R_0402_1005Metric"
		(layer "F.Cu")
		(at 136.74 121.06 90)
		(descr "Resistor SMD 0402")
		(tags "resistor SMD 0402")
		(property "Reference" "R1"
			(at 0.87 0.41 270)
			(layer "F.SilkS")
			(effects
				(font
					(size 0.7 0.7)
					(thickness 0.15)
				)
				(justify left bottom)
			)
		)
		(property "Value" "R_0R_0402"
			(at -1.011843 1.772047 90)
			(layer "F.Fab")
			(effects
				(font
					(size 0.7 0.7)
					(thickness 0.15)
				)
				(justify left bottom)
			)
		)
		(property "Datasheet" "https://industrial.panasonic.com/cdbs/www-data/pdf/RDA0000/AOA0000C301.pdf"
			(at 0 0 90)
			(layer "F.Fab")
			(hide yes)
			(effects
				(font
					(size 1.27 1.27)
					(thickness 0.15)
				)
			)
		)
		(property "Description" "SMD Chip Resistor, Jumper, 0 ohm, 100 mW, 0402 [1005 Metric], Thick Film, General Purpose"
			(at 0 0 90)
			(layer "F.Fab")
			(hide yes)
			(effects
				(font
					(size 1.27 1.27)
					(thickness 0.15)
				)
			)
		)
		(property "MPN" "ERJ2GE0R00X"
			(at 0 0 90)
			(unlocked yes)
			(layer "F.Fab")
			(hide yes)
			(effects
				(font
					(size 1 1)
					(thickness 0.15)
				)
			)
		)
		(property "Manufacturer" "Panasonic"
			(at 0 0 90)
			(unlocked yes)
			(layer "F.Fab")
			(hide yes)
			(effects
				(font
					(size 1 1)
					(thickness 0.15)
				)
			)
		)
		(property "License" "Apache-2.0"
			(at 0 0 90)
			(unlocked yes)
			(layer "F.Fab")
			(hide yes)
			(effects
				(font
					(size 1 1)
					(thickness 0.15)
				)
			)
		)
		(property "Author" "Antmicro"
			(at 0 0 90)
			(unlocked yes)
			(layer "F.Fab")
			(hide yes)
			(effects
				(font
					(size 1 1)
					(thickness 0.15)
				)
			)
		)
		(property "Val" "0R"
			(at 0 0 90)
			(unlocked yes)
			(layer "F.Fab")
			(hide yes)
			(effects
				(font
					(size 1 1)
					(thickness 0.15)
				)
			)
		)
		(property "Tolerance" ""
			(at 0 0 90)
			(unlocked yes)
			(layer "F.Fab")
			(hide yes)
			(effects
				(font
					(size 1 1)
					(thickness 0.15)
				)
			)
		)
		(property "Current" "1A"
			(at 0 0 90)
			(unlocked yes)
			(layer "F.Fab")
			(hide yes)
			(effects
				(font
					(size 1 1)
					(thickness 0.15)
				)
			)
		)
		(sheetname "/")
		(sheetfile "antmicro-m2-oculink-adapter-hw.kicad_sch")
		(attr smd)
		(fp_rect
			(start -0.925 -0.47)
			(end 0.925 0.47)
			(stroke
				(width 0.05)
				(type default)
			)
			(fill no)
			(layer "F.CrtYd")
		)
		(fp_rect
			(start -0.5 -0.25)
			(end 0.5 0.25)
			(stroke
				(width 0.15)
				(type solid)
			)
			(fill no)
			(layer "F.Fab")
		)
		(fp_text user "Author: Antmicro"
			(at -0.95 4.169 90)
			(layer "F.Fab")
			(effects
				(font
					(size 0.7 0.7)
					(thickness 0.15)
				)
				(justify left bottom)
			)
		)
		(fp_text user "License: Apache-2.0"
			(at -0.95 5.169 90)
			(layer "F.Fab")
			(effects
				(font
					(size 0.7 0.7)
					(thickness 0.15)
				)
				(justify left bottom)
			)
		)
		(fp_text user "${REFERENCE}"
			(at -0.95 3.168 90)
			(layer "F.Fab")
			(effects
				(font
					(size 0.7 0.7)
					(thickness 0.15)
				)
				(justify left bottom)
			)
		)
		(pad "1" smd roundrect
			(at -0.48 0 90)
			(size 0.59 0.64)
			(layers "F.Cu" "F.Mask" "F.Paste")
			(roundrect_rratio 0.25)
			(net 41 "Net-(J1-CLKREQ#)")
			(pintype "passive")
		)
		(pad "2" smd roundrect
			(at 0.48 0 90)
			(size 0.59 0.64)
			(layers "F.Cu" "F.Mask" "F.Paste")
			(roundrect_rratio 0.25)
			(net 1 "GND")
			(pintype "passive")
		)
	)
	(footprint "antmicro-footprints:R_0402_1005Metric"
		(layer "F.Cu")
		(at 140.1 89.66 180)
		(descr "Resistor SMD 0402")
		(tags "resistor SMD 0402")
		(property "Reference" "R11"
			(at -3 0.38 0)
			(layer "F.SilkS")
			(effects
				(font
					(size 0.7 0.7)
					(thickness 0.15)
				)
				(justify right top)
			)
		)
		(property "Value" "R_0R_0402"
			(at -1.011843 1.772047 0)
			(layer "F.Fab")
			(effects
				(font
					(size 0.7 0.7)
					(thickness 0.15)
				)
				(justify right top)
			)
		)
		(property "Datasheet" "https://industrial.panasonic.com/cdbs/www-data/pdf/RDA0000/AOA0000C301.pdf"
			(at 0 0 0)
			(layer "F.Fab")
			(hide yes)
			(effects
				(font
					(size 1.27 1.27)
					(thickness 0.15)
				)
			)
		)
		(property "Description" "SMD Chip Resistor, Jumper, 0 ohm, 100 mW, 0402 [1005 Metric], Thick Film, General Purpose"
			(at 0 0 0)
			(layer "F.Fab")
			(hide yes)
			(effects
				(font
					(size 1.27 1.27)
					(thickness 0.15)
				)
			)
		)
		(property "MPN" "ERJ2GE0R00X"
			(at 0 0 180)
			(unlocked yes)
			(layer "F.Fab")
			(hide yes)
			(effects
				(font
					(size 1 1)
					(thickness 0.15)
				)
			)
		)
		(property "Manufacturer" "Panasonic"
			(at 0 0 180)
			(unlocked yes)
			(layer "F.Fab")
			(hide yes)
			(effects
				(font
					(size 1 1)
					(thickness 0.15)
				)
			)
		)
		(property "License" "Apache-2.0"
			(at 0 0 180)
			(unlocked yes)
			(layer "F.Fab")
			(hide yes)
			(effects
				(font
					(size 1 1)
					(thickness 0.15)
				)
			)
		)
		(property "Author" "Antmicro"
			(at 0 0 180)
			(unlocked yes)
			(layer "F.Fab")
			(hide yes)
			(effects
				(font
					(size 1 1)
					(thickness 0.15)
				)
			)
		)
		(property "Val" "0R"
			(at 0 0 180)
			(unlocked yes)
			(layer "F.Fab")
			(hide yes)
			(effects
				(font
					(size 1 1)
					(thickness 0.15)
				)
			)
		)
		(property "Tolerance" ""
			(at 0 0 180)
			(unlocked yes)
			(layer "F.Fab")
			(hide yes)
			(effects
				(font
					(size 1 1)
					(thickness 0.15)
				)
			)
		)
		(property "Current" "1A"
			(at 0 0 180)
			(unlocked yes)
			(layer "F.Fab")
			(hide yes)
			(effects
				(font
					(size 1 1)
					(thickness 0.15)
				)
			)
		)
		(sheetname "/")
		(sheetfile "antmicro-m2-oculink-adapter-hw.kicad_sch")
		(attr smd)
		(fp_rect
			(start -0.925 -0.47)
			(end 0.925 0.47)
			(stroke
				(width 0.05)
				(type default)
			)
			(fill no)
			(layer "F.CrtYd")
		)
		(fp_rect
			(start -0.5 -0.25)
			(end 0.5 0.25)
			(stroke
				(width 0.15)
				(type solid)
			)
			(fill no)
			(layer "F.Fab")
		)
		(fp_text user "License: Apache-2.0"
			(at -0.95 5.169 0)
			(layer "F.Fab")
			(effects
				(font
					(size 0.7 0.7)
					(thickness 0.15)
				)
				(justify right top)
			)
		)
		(fp_text user "${REFERENCE}"
			(at -0.95 3.168 0)
			(layer "F.Fab")
			(effects
				(font
					(size 0.7 0.7)
					(thickness 0.15)
				)
				(justify right top)
			)
		)
		(fp_text user "Author: Antmicro"
			(at -0.95 4.169 0)
			(layer "F.Fab")
			(effects
				(font
					(size 0.7 0.7)
					(thickness 0.15)
				)
				(justify right top)
			)
		)
		(pad "1" smd roundrect
			(at -0.48 0 180)
			(size 0.59 0.64)
			(layers "F.Cu" "F.Mask" "F.Paste")
			(roundrect_rratio 0.25)
			(net 24 "/~{WAKEC}")
			(pintype "passive")
			(teardrops
				(best_length_ratio 0.5)
				(max_length 1)
				(best_width_ratio 1)
				(max_width 2)
				(curved_edges yes)
				(filter_ratio 0.9)
				(enabled no)
				(allow_two_segments yes)
				(prefer_zone_connections no)
			)
		)
		(pad "2" smd roundrect
			(at 0.48 0 180)
			(size 0.59 0.64)
			(layers "F.Cu" "F.Mask" "F.Paste")
			(roundrect_rratio 0.25)
			(net 37 "/~{WAKE}")
			(pintype "passive")
			(teardrops
				(best_length_ratio 0.5)
				(max_length 1)
				(best_width_ratio 1)
				(max_width 2)
				(curved_edges yes)
				(filter_ratio 0.9)
				(enabled no)
				(allow_two_segments yes)
				(prefer_zone_connections no)
			)
		)
	)
	(footprint "antmicro-footprints:C_0402_1005Metric"
		(layer "F.Cu")
		(at 136.71 124.19 -90)
		(descr "Capacitor SMD 0402")
		(tags "capacitor SMD 0402")
		(property "Reference" "C2"
			(at -2.32 0.39 90)
			(layer "F.SilkS")
			(effects
				(font
					(size 0.7 0.7)
					(thickness 0.15)
				)
				(justify right top)
			)
		)
		(property "Value" "C_100n_16V_X7R_0402"
			(at -1.022927 2.155213 90)
			(layer "F.Fab")
			(effects
				(font
					(size 0.7 0.7)
					(thickness 0.15)
				)
				(justify right top)
			)
		)
		(property "Datasheet" "https://www.kemet.com/en/us/capacitors/product/C0402C104J4RAC7411.html"
			(at 0 0 90)
			(layer "F.Fab")
			(hide yes)
			(effects
				(font
					(size 1.27 1.27)
					(thickness 0.15)
				)
			)
		)
		(property "Description" "SMD Multilayer Ceramic Capacitor, 100nF, 50V, 0402, ±5%, X7R"
			(at 0 0 90)
			(layer "F.Fab")
			(hide yes)
			(effects
				(font
					(size 1.27 1.27)
					(thickness 0.15)
				)
			)
		)
		(property "MPN" "C0402C104J4RAC7411"
			(at 0 0 270)
			(unlocked yes)
			(layer "F.Fab")
			(hide yes)
			(effects
				(font
					(size 1 1)
					(thickness 0.15)
				)
			)
		)
		(property "Val" "100n"
			(at 0 0 270)
			(unlocked yes)
			(layer "F.Fab")
			(hide yes)
			(effects
				(font
					(size 1 1)
					(thickness 0.15)
				)
			)
		)
		(property "Voltage" "16V"
			(at 0 0 270)
			(unlocked yes)
			(layer "F.Fab")
			(hide yes)
			(effects
				(font
					(size 1 1)
					(thickness 0.15)
				)
			)
		)
		(property "Dielectric" "X7R"
			(at 0 0 270)
			(unlocked yes)
			(layer "F.Fab")
			(hide yes)
			(effects
				(font
					(size 1 1)
					(thickness 0.15)
				)
			)
		)
		(property "Manufacturer" "KEMET"
			(at 0 0 270)
			(unlocked yes)
			(layer "F.Fab")
			(hide yes)
			(effects
				(font
					(size 1 1)
					(thickness 0.15)
				)
			)
		)
		(property "License" "Apache-2.0"
			(at 0 0 270)
			(unlocked yes)
			(layer "F.Fab")
			(hide yes)
			(effects
				(font
					(size 1 1)
					(thickness 0.15)
				)
			)
		)
		(property "Author" "Antmicro"
			(at 0 0 270)
			(unlocked yes)
			(layer "F.Fab")
			(hide yes)
			(effects
				(font
					(size 1 1)
					(thickness 0.15)
				)
			)
		)
		(sheetname "/")
		(sheetfile "antmicro-m2-oculink-adapter-hw.kicad_sch")
		(attr smd)
		(fp_rect
			(start -0.925 -0.47)
			(end 0.925 0.47)
			(stroke
				(width 0.05)
				(type default)
			)
			(fill no)
			(layer "F.CrtYd")
		)
		(fp_line
			(start -0.494 0.248)
			(end -0.494 -0.25)
			(stroke
				(width 0.15)
				(type solid)
			)
			(layer "F.Fab")
		)
		(fp_line
			(start 0.504 0.248)
			(end -0.494 0.248)
			(stroke
				(width 0.15)
				(type solid)
			)
			(layer "F.Fab")
		)
		(fp_line
			(start -0.494 -0.25)
			(end 0.504 -0.25)
			(stroke
				(width 0.15)
				(type solid)
			)
			(layer "F.Fab")
		)
		(fp_line
			(start 0.504 -0.25)
			(end 0.504 0.248)
			(stroke
				(width 0.15)
				(type solid)
			)
			(layer "F.Fab")
		)
		(fp_text user "License: Apache-2.0"
			(at -0.939 5.799 90)
			(layer "F.Fab")
			(effects
				(font
					(size 0.7 0.7)
					(thickness 0.15)
				)
				(justify right top)
			)
		)
		(fp_text user "${REFERENCE}"
			(at -0.939 4.599 90)
			(layer "F.Fab")
			(effects
				(font
					(size 0.7 0.7)
					(thickness 0.15)
				)
				(justify right top)
			)
		)
		(fp_text user "Author: Antmicro"
			(at -0.939 3.399 90)
			(layer "F.Fab")
			(effects
				(font
					(size 0.7 0.7)
					(thickness 0.15)
				)
				(justify right top)
			)
		)
		(pad "1" smd roundrect
			(at -0.48 0 270)
			(size 0.59 0.64)
			(layers "F.Cu" "F.Mask" "F.Paste")
			(roundrect_rratio 0.25)
			(net 1 "GND")
			(pintype "passive")
		)
		(pad "2" smd roundrect
			(at 0.48 0 270)
			(size 0.59 0.64)
			(layers "F.Cu" "F.Mask" "F.Paste")
			(roundrect_rratio 0.25)
			(net 56 "Net-(C1-Pad2)")
			(pintype "passive")
		)
	)
	(footprint "antmicro-footprints:PCB-Edge_M.2_Key-M"
		(locked yes)
		(layer "F.Cu")
		(at 146.3 130.6)
		(property "Reference" "J1"
			(at 10.05 -5.7 0)
			(layer "F.SilkS")
			(hide yes)
			(effects
				(font
					(size 0.7 0.7)
					(thickness 0.15)
				)
				(justify left bottom)
			)
		)
		(property "Value" "PCB-Edge_M.2_Key-M"
			(at -0.075 2.25 0)
			(layer "F.Fab")
			(effects
				(font
					(size 0.7 0.7)
					(thickness 0.15)
				)
				(justify left bottom)
			)
		)
		(property "Datasheet" "https://www.amphenol-icc.com/media/wysiwyg/files/drawing/10130618.pdf"
			(at 0 0 0)
			(layer "F.Fab")
			(hide yes)
			(effects
				(font
					(size 1.27 1.27)
					(thickness 0.15)
				)
			)
		)
		(property "Description" "PCB Edge for M.2 key M"
			(at 0 0 0)
			(layer "F.Fab")
			(hide yes)
			(effects
				(font
					(size 1.27 1.27)
					(thickness 0.15)
				)
			)
		)
		(property "Author" "Antmicro"
			(at 0 0 0)
			(unlocked yes)
			(layer "F.Fab")
			(hide yes)
			(effects
				(font
					(size 1 1)
					(thickness 0.15)
				)
			)
		)
		(property "License" "Apache-2.0"
			(at 0 0 0)
			(unlocked yes)
			(layer "F.Fab")
			(hide yes)
			(effects
				(font
					(size 1 1)
					(thickness 0.15)
				)
			)
		)
		(sheetname "/")
		(sheetfile "antmicro-m2-oculink-adapter-hw.kicad_sch")
		(clearance 0)
		(attr exclude_from_pos_files exclude_from_bom)
		(fp_rect
			(start -11.15 -5.2)
			(end 10.85 0)
			(stroke
				(width 0.05)
				(type solid)
			)
			(fill no)
			(layer "B.CrtYd")
		)
		(fp_rect
			(start -10.075 0)
			(end 9.775 -4)
			(stroke
				(width 0.05)
				(type solid)
			)
			(fill no)
			(layer "F.CrtYd")
		)
		(fp_text user "${REFERENCE}"
			(at -11.15 4.25 0)
			(layer "F.Fab")
			(effects
				(font
					(size 0.7 0.7)
					(thickness 0.15)
				)
				(justify left bottom)
			)
		)
		(fp_text user "License: Apache-2.0"
			(at -11.15 6.65 0)
			(layer "F.Fab")
			(effects
				(font
					(size 0.7 0.7)
					(thickness 0.15)
				)
				(justify left bottom)
			)
		)
		(fp_text user "Author: Antmicro"
			(at -11.15 5.45 0)
			(layer "F.Fab")
			(effects
				(font
					(size 0.7 0.7)
					(thickness 0.15)
				)
				(justify left bottom)
			)
		)
		(pad "1" smd rect
			(at 9.1 -1.45)
			(size 0.35 2.5)
			(layers "F.Cu" "F.Mask")
			(net 1 "GND")
			(pinfunction "GND")
			(pintype "passive")
			(teardrops
				(best_length_ratio 0.5)
				(max_length 1)
				(best_width_ratio 1)
				(max_width 2)
				(curved_edges yes)
				(filter_ratio 0.9)
				(enabled no)
				(allow_two_segments yes)
				(prefer_zone_connections no)
			)
		)
		(pad "2" smd rect
			(at 8.845243 -1.7)
			(size 0.35 3)
			(layers "B.Cu" "B.Mask")
			(net 56 "Net-(C1-Pad2)")
			(pinfunction "3.3V")
			(pintype "passive")
			(teardrops
				(best_length_ratio 0.5)
				(max_length 1)
				(best_width_ratio 1)
				(max_width 2)
				(curved_edges yes)
				(filter_ratio 0.9)
				(enabled no)
				(allow_two_segments yes)
				(prefer_zone_connections no)
			)
		)
		(pad "3" smd rect
			(at 8.6 -1.45)
			(size 0.35 2.5)
			(layers "F.Cu" "F.Mask")
			(net 1 "GND")
			(pinfunction "GND")
			(pintype "passive")
			(teardrops
				(best_length_ratio 0.5)
				(max_length 1)
				(best_width_ratio 1)
				(max_width 2)
				(curved_edges yes)
				(filter_ratio 0.9)
				(enabled no)
				(allow_two_segments yes)
				(prefer_zone_connections no)
			)
		)
		(pad "4" smd rect
			(at 8.345243 -1.7)
			(size 0.35 3)
			(layers "B.Cu" "B.Mask")
			(net 56 "Net-(C1-Pad2)")
			(pinfunction "3.3V")
			(pintype "passive")
			(teardrops
				(best_length_ratio 0.5)
				(max_length 1)
				(best_width_ratio 1)
				(max_width 2)
				(curved_edges yes)
				(filter_ratio 0.9)
				(enabled no)
				(allow_two_segments yes)
				(prefer_zone_connections no)
			)
		)
		(pad "5" smd rect
			(at 8.1 -1.45)
			(size 0.35 2.5)
			(layers "F.Cu" "F.Mask")
			(net 6 "/PCIe_{x4}.RX3-")
			(pinfunction "PERn3")
			(pintype "passive")
			(teardrops
				(best_length_ratio 0.5)
				(max_length 1)
				(best_width_ratio 1)
				(max_width 2)
				(curved_edges yes)
				(filter_ratio 0.9)
				(enabled no)
				(allow_two_segments yes)
				(prefer_zone_connections no)
			)
		)
		(pad "6" smd rect
			(at 7.845243 -1.7)
			(size 0.35 3)
			(layers "B.Cu" "B.Mask")
			(net 49 "unconnected-(J1-NC-Pad6)")
			(pinfunction "NC")
			(pintype "no_connect")
			(teardrops
				(best_length_ratio 0.5)
				(max_length 1)
				(best_width_ratio 1)
				(max_width 2)
				(curved_edges yes)
				(filter_ratio 0.9)
				(enabled no)
				(allow_two_segments yes)
				(prefer_zone_connections no)
			)
		)
		(pad "7" smd rect
			(at 7.6 -1.45)
			(size 0.35 2.5)
			(layers "F.Cu" "F.Mask")
			(net 9 "/PCIe_{x4}.RX3+")
			(pinfunction "PERp3")
			(pintype "passive")
			(teardrops
				(best_length_ratio 0.5)
				(max_length 1)
				(best_width_ratio 1)
				(max_width 2)
				(curved_edges yes)
				(filter_ratio 0.9)
				(enabled no)
				(allow_two_segments yes)
				(prefer_zone_connections no)
			)
		)
		(pad "8" smd rect
			(at 7.345243 -1.7)
			(size 0.35 3)
			(layers "B.Cu" "B.Mask")
			(net 43 "unconnected-(J1-NC-Pad8)")
			(pinfunction "NC")
			(pintype "no_connect")
			(teardrops
				(best_length_ratio 0.5)
				(max_length 1)
				(best_width_ratio 1)
				(max_width 2)
				(curved_edges yes)
				(filter_ratio 0.9)
				(enabled no)
				(allow_two_segments yes)
				(prefer_zone_connections no)
			)
		)
		(pad "9" smd rect
			(at 7.1 -1.45)
			(size 0.35 2.5)
			(layers "F.Cu" "F.Mask")
			(net 1 "GND")
			(pinfunction "GND")
			(pintype "passive")
			(teardrops
				(best_length_ratio 0.5)
				(max_length 1)
				(best_width_ratio 1)
				(max_width 2)
				(curved_edges yes)
				(filter_ratio 0.9)
				(enabled no)
				(allow_two_segments yes)
				(prefer_zone_connections no)
			)
		)
		(pad "10" smd rect
			(at 6.845243 -1.7)
			(size 0.35 3)
			(layers "B.Cu" "B.Mask")
			(net 35 "unconnected-(J1-DAS-Pad10)")
			(pinfunction "DAS")
			(pintype "passive+no_connect")
			(teardrops
				(best_length_ratio 0.5)
				(max_length 1)
				(best_width_ratio 1)
				(max_width 2)
				(curved_edges yes)
				(filter_ratio 0.9)
				(enabled no)
				(allow_two_segments yes)
				(prefer_zone_connections no)
			)
		)
		(pad "11" smd rect
			(at 6.6 -1.45)
			(size 0.35 2.5)
			(layers "F.Cu" "F.Mask")
			(net 21 "/PCIe_{x4}.TX3-")
			(pinfunction "PETn3")
			(pintype "passive")
			(teardrops
				(best_length_ratio 0.5)
				(max_length 1)
				(best_width_ratio 1)
				(max_width 2)
				(curved_edges yes)
				(filter_ratio 0.9)
				(enabled no)
				(allow_two_segments yes)
				(prefer_zone_connections no)
			)
		)
		(pad "12" smd rect
			(at 6.345243 -1.7)
			(size 0.35 3)
			(layers "B.Cu" "B.Mask")
			(net 56 "Net-(C1-Pad2)")
			(pinfunction "3.3V")
			(pintype "power_in")
			(teardrops
				(best_length_ratio 0.5)
				(max_length 1)
				(best_width_ratio 1)
				(max_width 2)
				(curved_edges yes)
				(filter_ratio 0.9)
				(enabled no)
				(allow_two_segments yes)
				(prefer_zone_connections no)
			)
		)
		(pad "13" smd rect
			(at 6.1 -1.45)
			(size 0.35 2.5)
			(layers "F.Cu" "F.Mask")
			(net 2 "/PCIe_{x4}.TX3+")
			(pinfunction "PETp3")
			(pintype "passive")
			(teardrops
				(best_length_ratio 0.5)
				(max_length 1)
				(best_width_ratio 1)
				(max_width 2)
				(curved_edges yes)
				(filter_ratio 0.9)
				(enabled no)
				(allow_two_segments yes)
				(prefer_zone_connections no)
			)
		)
		(pad "14" smd rect
			(at 5.845243 -1.7)
			(size 0.35 3)
			(layers "B.Cu" "B.Mask")
			(net 56 "Net-(C1-Pad2)")
			(pinfunction "3.3V")
			(pintype "passive")
			(teardrops
				(best_length_ratio 0.5)
				(max_length 1)
				(best_width_ratio 1)
				(max_width 2)
				(curved_edges yes)
				(filter_ratio 0.9)
				(enabled no)
				(allow_two_segments yes)
				(prefer_zone_connections no)
			)
		)
		(pad "15" smd rect
			(at 5.6 -1.45)
			(size 0.35 2.5)
			(layers "F.Cu" "F.Mask")
			(net 1 "GND")
			(pinfunction "GND")
			(pintype "passive")
			(teardrops
				(best_length_ratio 0.5)
				(max_length 1)
				(best_width_ratio 1)
				(max_width 2)
				(curved_edges yes)
				(filter_ratio 0.9)
				(enabled no)
				(allow_two_segments yes)
				(prefer_zone_connections no)
			)
		)
		(pad "16" smd rect
			(at 5.345243 -1.7)
			(size 0.35 3)
			(layers "B.Cu" "B.Mask")
			(net 56 "Net-(C1-Pad2)")
			(pinfunction "3.3V")
			(pintype "passive")
			(teardrops
				(best_length_ratio 0.5)
				(max_length 1)
				(best_width_ratio 1)
				(max_width 2)
				(curved_edges yes)
				(filter_ratio 0.9)
				(enabled no)
				(allow_two_segments yes)
				(prefer_zone_connections no)
			)
		)
		(pad "17" smd rect
			(at 5.1 -1.45)
			(size 0.35 2.5)
			(layers "F.Cu" "F.Mask")
			(net 14 "/PCIe_{x4}.RX2-")
			(pinfunction "PERn2")
			(pintype "passive")
			(teardrops
				(best_length_ratio 0.5)
				(max_length 1)
				(best_width_ratio 1)
				(max_width 2)
				(curved_edges yes)
				(filter_ratio 0.9)
				(enabled no)
				(allow_two_segments yes)
				(prefer_zone_connections no)
			)
		)
		(pad "18" smd rect
			(at 4.845243 -1.7)
			(size 0.35 3)
			(layers "B.Cu" "B.Mask")
			(net 56 "Net-(C1-Pad2)")
			(pinfunction "3.3V")
			(pintype "passive")
			(teardrops
				(best_length_ratio 0.5)
				(max_length 1)
				(best_width_ratio 1)
				(max_width 2)
				(curved_edges yes)
				(filter_ratio 0.9)
				(enabled no)
				(allow_two_segments yes)
				(prefer_zone_connections no)
			)
		)
		(pad "19" smd rect
			(at 4.6 -1.45)
			(size 0.35 2.5)
			(layers "F.Cu" "F.Mask")
			(net 4 "/PCIe_{x4}.RX2+")
			(pinfunction "PERp2")
			(pintype "passive")
			(teardrops
				(best_length_ratio 0.5)
				(max_length 1)
				(best_width_ratio 1)
				(max_width 2)
				(curved_edges yes)
				(filter_ratio 0.9)
				(enabled no)
				(allow_two_segments yes)
				(prefer_zone_connections no)
			)
		)
		(pad "20" smd rect
			(at 4.345243 -1.7)
			(size 0.35 3)
			(layers "B.Cu" "B.Mask")
			(net 42 "unconnected-(J1-NC-Pad20)")
			(pinfunction "NC")
			(pintype "no_connect")
			(teardrops
				(best_length_ratio 0.5)
				(max_length 1)
				(best_width_ratio 1)
				(max_width 2)
				(curved_edges yes)
				(filter_ratio 0.9)
				(enabled no)
				(allow_two_segments yes)
				(prefer_zone_connections no)
			)
		)
		(pad "21" smd rect
			(at 4.1 -1.45)
			(size 0.35 2.5)
			(layers "F.Cu" "F.Mask")
			(net 1 "GND")
			(pinfunction "GND")
			(pintype "passive")
			(teardrops
				(best_length_ratio 0.5)
				(max_length 1)
				(best_width_ratio 1)
				(max_width 2)
				(curved_edges yes)
				(filter_ratio 0.9)
				(enabled no)
				(allow_two_segments yes)
				(prefer_zone_connections no)
			)
		)
		(pad "22" smd rect
			(at 3.845243 -1.7)
			(size 0.35 3)
			(layers "B.Cu" "B.Mask")
			(net 18 "unconnected-(J1-NC-Pad22)")
			(pinfunction "NC")
			(pintype "no_connect")
			(teardrops
				(best_length_ratio 0.5)
				(max_length 1)
				(best_width_ratio 1)
				(max_width 2)
				(curved_edges yes)
				(filter_ratio 0.9)
				(enabled no)
				(allow_two_segments yes)
				(prefer_zone_connections no)
			)
		)
		(pad "23" smd rect
			(at 3.6 -1.45)
			(size 0.35 2.5)
			(layers "F.Cu" "F.Mask")
			(net 10 "/PCIe_{x4}.TX2-")
			(pinfunction "PETn2")
			(pintype "passive")
			(teardrops
				(best_length_ratio 0.5)
				(max_length 1)
				(best_width_ratio 1)
				(max_width 2)
				(curved_edges yes)
				(filter_ratio 0.9)
				(enabled no)
				(allow_two_segments yes)
				(prefer_zone_connections no)
			)
		)
		(pad "24" smd rect
			(at 3.345243 -1.7)
			(size 0.35 3)
			(layers "B.Cu" "B.Mask")
			(net 34 "unconnected-(J1-NC-Pad24)")
			(pinfunction "NC")
			(pintype "no_connect")
			(teardrops
				(best_length_ratio 0.5)
				(max_length 1)
				(best_width_ratio 1)
				(max_width 2)
				(curved_edges yes)
				(filter_ratio 0.9)
				(enabled no)
				(allow_two_segments yes)
				(prefer_zone_connections no)
			)
		)
		(pad "25" smd rect
			(at 3.1 -1.45)
			(size 0.35 2.5)
			(layers "F.Cu" "F.Mask")
			(net 5 "/PCIe_{x4}.TX2+")
			(pinfunction "PETp2")
			(pintype "passive")
			(teardrops
				(best_length_ratio 0.5)
				(max_length 1)
				(best_width_ratio 1)
				(max_width 2)
				(curved_edges yes)
				(filter_ratio 0.9)
				(enabled no)
				(allow_two_segments yes)
				(prefer_zone_connections no)
			)
		)
		(pad "26" smd rect
			(at 2.845243 -1.7)
			(size 0.35 3)
			(layers "B.Cu" "B.Mask")
			(net 45 "unconnected-(J1-NC-Pad26)")
			(pinfunction "NC")
			(pintype "no_connect")
			(teardrops
				(best_length_ratio 0.5)
				(max_length 1)
				(best_width_ratio 1)
				(max_width 2)
				(curved_edges yes)
				(filter_ratio 0.9)
				(enabled no)
				(allow_two_segments yes)
				(prefer_zone_connections no)
			)
		)
		(pad "27" smd rect
			(at 2.6 -1.45)
			(size 0.35 2.5)
			(layers "F.Cu" "F.Mask")
			(net 1 "GND")
			(pinfunction "GND")
			(pintype "passive")
			(teardrops
				(best_length_ratio 0.5)
				(max_length 1)
				(best_width_ratio 1)
				(max_width 2)
				(curved_edges yes)
				(filter_ratio 0.9)
				(enabled no)
				(allow_two_segments yes)
				(prefer_zone_connections no)
			)
		)
		(pad "28" smd rect
			(at 2.345243 -1.7)
			(size 0.35 3)
			(layers "B.Cu" "B.Mask")
			(net 48 "unconnected-(J1-NC-Pad28)")
			(pinfunction "NC")
			(pintype "no_connect")
			(teardrops
				(best_length_ratio 0.5)
				(max_length 1)
				(best_width_ratio 1)
				(max_width 2)
				(curved_edges yes)
				(filter_ratio 0.9)
				(enabled no)
				(allow_two_segments yes)
				(prefer_zone_connections no)
			)
		)
		(pad "29" smd rect
			(at 2.1 -1.45)
			(size 0.35 2.5)
			(layers "F.Cu" "F.Mask")
			(net 27 "/PCIe_{x4}.RX1-")
			(pinfunction "PERn1")
			(pintype "passive")
			(teardrops
				(best_length_ratio 0.5)
				(max_length 1)
				(best_width_ratio 1)
				(max_width 2)
				(curved_edges yes)
				(filter_ratio 0.9)
				(enabled no)
				(allow_two_segments yes)
				(prefer_zone_connections no)
			)
		)
		(pad "30" smd rect
			(at 1.845243 -1.7)
			(size 0.35 3)
			(layers "B.Cu" "B.Mask")
			(net 19 "unconnected-(J1-NC-Pad30)")
			(pinfunction "NC")
			(pintype "no_connect")
			(teardrops
				(best_length_ratio 0.5)
				(max_length 1)
				(best_width_ratio 1)
				(max_width 2)
				(curved_edges yes)
				(filter_ratio 0.9)
				(enabled no)
				(allow_two_segments yes)
				(prefer_zone_connections no)
			)
		)
		(pad "31" smd rect
			(at 1.6 -1.45)
			(size 0.35 2.5)
			(layers "F.Cu" "F.Mask")
			(net 16 "/PCIe_{x4}.RX1+")
			(pinfunction "PERp1")
			(pintype "passive")
			(teardrops
				(best_length_ratio 0.5)
				(max_length 1)
				(best_width_ratio 1)
				(max_width 2)
				(curved_edges yes)
				(filter_ratio 0.9)
				(enabled no)
				(allow_two_segments yes)
				(prefer_zone_connections no)
			)
		)
		(pad "32" smd rect
			(at 1.345243 -1.7)
			(size 0.35 3)
			(layers "B.Cu" "B.Mask")
			(net 31 "unconnected-(J1-NC-Pad32)")
			(pinfunction "NC")
			(pintype "no_connect")
			(teardrops
				(best_length_ratio 0.5)
				(max_length 1)
				(best_width_ratio 1)
				(max_width 2)
				(curved_edges yes)
				(filter_ratio 0.9)
				(enabled no)
				(allow_two_segments yes)
				(prefer_zone_connections no)
			)
		)
		(pad "33" smd rect
			(at 1.1 -1.45)
			(size 0.35 2.5)
			(layers "F.Cu" "F.Mask")
			(net 1 "GND")
			(pinfunction "GND")
			(pintype "passive")
			(teardrops
				(best_length_ratio 0.5)
				(max_length 1)
				(best_width_ratio 1)
				(max_width 2)
				(curved_edges yes)
				(filter_ratio 0.9)
				(enabled no)
				(allow_two_segments yes)
				(prefer_zone_connections no)
			)
		)
		(pad "34" smd rect
			(at 0.845243 -1.7)
			(size 0.35 3)
			(layers "B.Cu" "B.Mask")
			(net 44 "unconnected-(J1-NC-Pad34)")
			(pinfunction "NC")
			(pintype "no_connect")
			(teardrops
				(best_length_ratio 0.5)
				(max_length 1)
				(best_width_ratio 1)
				(max_width 2)
				(curved_edges yes)
				(filter_ratio 0.9)
				(enabled no)
				(allow_two_segments yes)
				(prefer_zone_connections no)
			)
		)
		(pad "35" smd rect
			(at 0.6 -1.45)
			(size 0.35 2.5)
			(layers "F.Cu" "F.Mask")
			(net 8 "/PCIe_{x4}.TX1-")
			(pinfunction "PETn1")
			(pintype "passive")
			(teardrops
				(best_length_ratio 0.5)
				(max_length 1)
				(best_width_ratio 1)
				(max_width 2)
				(curved_edges yes)
				(filter_ratio 0.9)
				(enabled no)
				(allow_two_segments yes)
				(prefer_zone_connections no)
			)
		)
		(pad "36" smd rect
			(at 0.345243 -1.7)
			(size 0.35 3)
			(layers "B.Cu" "B.Mask")
			(net 29 "unconnected-(J1-NC-Pad36)")
			(pinfunction "NC")
			(pintype "no_connect")
			(teardrops
				(best_length_ratio 0.5)
				(max_length 1)
				(best_width_ratio 1)
				(max_width 2)
				(curved_edges yes)
				(filter_ratio 0.9)
				(enabled no)
				(allow_two_segments yes)
				(prefer_zone_connections no)
			)
		)
		(pad "37" smd rect
			(at 0.1 -1.45)
			(size 0.35 2.5)
			(layers "F.Cu" "F.Mask")
			(net 3 "/PCIe_{x4}.TX1+")
			(pinfunction "PETp1")
			(pintype "passive")
			(teardrops
				(best_length_ratio 0.5)
				(max_length 1)
				(best_width_ratio 1)
				(max_width 2)
				(curved_edges yes)
				(filter_ratio 0.9)
				(enabled no)
				(allow_two_segments yes)
				(prefer_zone_connections no)
			)
		)
		(pad "38" smd rect
			(at -0.154757 -1.7)
			(size 0.35 3)
			(layers "B.Cu" "B.Mask")
			(net 32 "unconnected-(J1-DEVSLP-Pad38)")
			(pinfunction "DEVSLP")
			(pintype "passive+no_connect")
			(teardrops
				(best_length_ratio 0.5)
				(max_length 1)
				(best_width_ratio 1)
				(max_width 2)
				(curved_edges yes)
				(filter_ratio 0.9)
				(enabled no)
				(allow_two_segments yes)
				(prefer_zone_connections no)
			)
		)
		(pad "39" smd rect
			(at -0.4 -1.45)
			(size 0.35 2.5)
			(layers "F.Cu" "F.Mask")
			(net 1 "GND")
			(pinfunction "GND")
			(pintype "passive")
			(teardrops
				(best_length_ratio 0.5)
				(max_length 1)
				(best_width_ratio 1)
				(max_width 2)
				(curved_edges yes)
				(filter_ratio 0.9)
				(enabled no)
				(allow_two_segments yes)
				(prefer_zone_connections no)
			)
		)
		(pad "40" smd rect
			(at -0.654757 -1.7)
			(size 0.35 3)
			(layers "B.Cu" "B.Mask")
			(net 28 "unconnected-(J1-NC-Pad40)")
			(pinfunction "NC")
			(pintype "no_connect")
			(teardrops
				(best_length_ratio 0.5)
				(max_length 1)
				(best_width_ratio 1)
				(max_width 2)
				(curved_edges yes)
				(filter_ratio 0.9)
				(enabled no)
				(allow_two_segments yes)
				(prefer_zone_connections no)
			)
		)
		(pad "41" smd rect
			(at -0.9 -1.45)
			(size 0.35 2.5)
			(layers "F.Cu" "F.Mask")
			(net 7 "/PCIe_{x4}.RX0-")
			(pinfunction "PERn0")
			(pintype "passive")
			(teardrops
				(best_length_ratio 0.5)
				(max_length 1)
				(best_width_ratio 1)
				(max_width 2)
				(curved_edges yes)
				(filter_ratio 0.9)
				(enabled no)
				(allow_two_segments yes)
				(prefer_zone_connections no)
			)
		)
		(pad "42" smd rect
			(at -1.154757 -1.7)
			(size 0.35 3)
			(layers "B.Cu" "B.Mask")
			(net 46 "unconnected-(J1-NC-Pad42)")
			(pinfunction "NC")
			(pintype "no_connect")
			(teardrops
				(best_length_ratio 0.5)
				(max_length 1)
				(best_width_ratio 1)
				(max_width 2)
				(curved_edges yes)
				(filter_ratio 0.9)
				(enabled no)
				(allow_two_segments yes)
				(prefer_zone_connections no)
			)
		)
		(pad "43" smd rect
			(at -1.4 -1.45)
			(size 0.35 2.5)
			(layers "F.Cu" "F.Mask")
			(net 26 "/PCIe_{x4}.RX0+")
			(pinfunction "PERp0")
			(pintype "passive")
			(teardrops
				(best_length_ratio 0.5)
				(max_length 1)
				(best_width_ratio 1)
				(max_width 2)
				(curved_edges yes)
				(filter_ratio 0.9)
				(enabled no)
				(allow_two_segments yes)
				(prefer_zone_connections no)
			)
		)
		(pad "44" smd rect
			(at -1.654757 -1.7)
			(size 0.35 3)
			(layers "B.Cu" "B.Mask")
			(net 40 "unconnected-(J1-NC-Pad44)")
			(pinfunction "NC")
			(pintype "no_connect")
			(teardrops
				(best_length_ratio 0.5)
				(max_length 1)
				(best_width_ratio 1)
				(max_width 2)
				(curved_edges yes)
				(filter_ratio 0.9)
				(enabled no)
				(allow_two_segments yes)
				(prefer_zone_connections no)
			)
		)
		(pad "45" smd rect
			(at -1.9 -1.45)
			(size 0.35 2.5)
			(layers "F.Cu" "F.Mask")
			(net 1 "GND")
			(pinfunction "GND")
			(pintype "passive")
			(teardrops
				(best_length_ratio 0.5)
				(max_length 1)
				(best_width_ratio 1)
				(max_width 2)
				(curved_edges yes)
				(filter_ratio 0.9)
				(enabled no)
				(allow_two_segments yes)
				(prefer_zone_connections no)
			)
		)
		(pad "46" smd rect
			(at -2.154757 -1.7)
			(size 0.35 3)
			(layers "B.Cu" "B.Mask")
			(net 47 "unconnected-(J1-NC-Pad46)")
			(pinfunction "NC")
			(pintype "no_connect")
			(teardrops
				(best_length_ratio 0.5)
				(max_length 1)
				(best_width_ratio 1)
				(max_width 2)
				(curved_edges yes)
				(filter_ratio 0.9)
				(enabled no)
				(allow_two_segments yes)
				(prefer_zone_connections no)
			)
		)
		(pad "47" smd rect
			(at -2.4 -1.45)
			(size 0.35 2.5)
			(layers "F.Cu" "F.Mask")
			(net 15 "/PCIe_{x4}.TX0-")
			(pinfunction "PETn0")
			(pintype "passive")
			(teardrops
				(best_length_ratio 0.5)
				(max_length 1)
				(best_width_ratio 1)
				(max_width 2)
				(curved_edges yes)
				(filter_ratio 0.9)
				(enabled no)
				(allow_two_segments yes)
				(prefer_zone_connections no)
			)
		)
		(pad "48" smd rect
			(at -2.654757 -1.7)
			(size 0.35 3)
			(layers "B.Cu" "B.Mask")
			(net 22 "unconnected-(J1-NC-Pad48)")
			(pinfunction "NC")
			(pintype "no_connect")
			(teardrops
				(best_length_ratio 0.5)
				(max_length 1)
				(best_width_ratio 1)
				(max_width 2)
				(curved_edges yes)
				(filter_ratio 0.9)
				(enabled no)
				(allow_two_segments yes)
				(prefer_zone_connections no)
			)
		)
		(pad "49" smd rect
			(at -2.9 -1.45)
			(size 0.35 2.5)
			(layers "F.Cu" "F.Mask")
			(net 25 "/PCIe_{x4}.TX0+")
			(pinfunction "PETp0")
			(pintype "passive")
			(teardrops
				(best_length_ratio 0.5)
				(max_length 1)
				(best_width_ratio 1)
				(max_width 2)
				(curved_edges yes)
				(filter_ratio 0.9)
				(enabled no)
				(allow_two_segments yes)
				(prefer_zone_connections no)
			)
		)
		(pad "50" smd rect
			(at -3.154757 -1.7)
			(size 0.35 3)
			(layers "B.Cu" "B.Mask")
			(net 55 "/~{PERST}")
			(pinfunction "PERST#")
			(pintype "passive")
			(teardrops
				(best_length_ratio 0.5)
				(max_length 1)
				(best_width_ratio 1)
				(max_width 2)
				(curved_edges yes)
				(filter_ratio 0.9)
				(enabled no)
				(allow_two_segments yes)
				(prefer_zone_connections no)
			)
		)
		(pad "51" smd rect
			(at -3.4 -1.45)
			(size 0.35 2.5)
			(layers "F.Cu" "F.Mask")
			(net 1 "GND")
			(pinfunction "GND")
			(pintype "passive")
			(teardrops
				(best_length_ratio 0.5)
				(max_length 1)
				(best_width_ratio 1)
				(max_width 2)
				(curved_edges yes)
				(filter_ratio 0.9)
				(enabled no)
				(allow_two_segments yes)
				(prefer_zone_connections no)
			)
		)
		(pad "52" smd rect
			(at -3.654757 -1.7)
			(size 0.35 3)
			(layers "B.Cu" "B.Mask")
			(net 41 "Net-(J1-CLKREQ#)")
			(pinfunction "CLKREQ#")
			(pintype "passive")
			(teardrops
				(best_length_ratio 0.5)
				(max_length 1)
				(best_width_ratio 1)
				(max_width 2)
				(curved_edges yes)
				(filter_ratio 0.9)
				(enabled no)
				(allow_two_segments yes)
				(prefer_zone_connections no)
			)
		)
		(pad "53" smd rect
			(at -3.9 -1.45)
			(size 0.35 2.5)
			(layers "F.Cu" "F.Mask")
			(net 36 "/PCIe_{REF0}.CK+")
			(pinfunction "REFCLKn")
			(pintype "passive")
			(teardrops
				(best_length_ratio 0.5)
				(max_length 1)
				(best_width_ratio 1)
				(max_width 2)
				(curved_edges yes)
				(filter_ratio 0.9)
				(enabled no)
				(allow_two_segments yes)
				(prefer_zone_connections no)
			)
		)
		(pad "54" smd rect
			(at -4.154757 -1.7)
			(size 0.35 3)
			(layers "B.Cu" "B.Mask")
			(net 37 "/~{WAKE}")
			(pinfunction "PEWAKE#")
			(pintype "passive")
			(teardrops
				(best_length_ratio 0.5)
				(max_length 1)
				(best_width_ratio 1)
				(max_width 2)
				(curved_edges yes)
				(filter_ratio 0.9)
				(enabled no)
				(allow_two_segments yes)
				(prefer_zone_connections no)
			)
		)
		(pad "55" smd rect
			(at -4.4 -1.45)
			(size 0.35 2.5)
			(layers "F.Cu" "F.Mask")
			(net 38 "/PCIe_{REF0}.CK-")
			(pinfunction "REFCLKp")
			(pintype "passive")
			(teardrops
				(best_length_ratio 0.5)
				(max_length 1)
				(best_width_ratio 1)
				(max_width 2)
				(curved_edges yes)
				(filter_ratio 0.9)
				(enabled no)
				(allow_two_segments yes)
				(prefer_zone_connections no)
			)
		)
		(pad "56" smd rect
			(at -4.654757 -1.7)
			(size 0.35 3)
			(layers "B.Cu" "B.Mask")
			(net 39 "unconnected-(J1-NC-Pad56)")
			(pinfunction "NC")
			(pintype "no_connect")
			(teardrops
				(best_length_ratio 0.5)
				(max_length 1)
				(best_width_ratio 1)
				(max_width 2)
				(curved_edges yes)
				(filter_ratio 0.9)
				(enabled no)
				(allow_two_segments yes)
				(prefer_zone_connections no)
			)
		)
		(pad "57" smd rect
			(at -4.9 -1.45)
			(size 0.35 2.5)
			(layers "F.Cu" "F.Mask")
			(net 1 "GND")
			(pinfunction "GND")
			(pintype "passive")
			(teardrops
				(best_length_ratio 0.5)
				(max_length 1)
				(best_width_ratio 1)
				(max_width 2)
				(curved_edges yes)
				(filter_ratio 0.9)
				(enabled no)
				(allow_two_segments yes)
				(prefer_zone_connections no)
			)
		)
		(pad "58" smd rect
			(at -5.154757 -1.7)
			(size 0.35 3)
			(layers "B.Cu" "B.Mask")
			(net 20 "unconnected-(J1-NC-Pad58)")
			(pinfunction "NC")
			(pintype "no_connect")
			(teardrops
				(best_length_ratio 0.5)
				(max_length 1)
				(best_width_ratio 1)
				(max_width 2)
				(curved_edges yes)
				(filter_ratio 0.9)
				(enabled no)
				(allow_two_segments yes)
				(prefer_zone_connections no)
			)
		)
		(pad "67" smd rect
			(at -7.4 -1.45)
			(size 0.35 2.5)
			(layers "F.Cu" "F.Mask")
			(net 30 "unconnected-(J1-NC-Pad67)")
			(pinfunction "NC")
			(pintype "no_connect")
			(teardrops
				(best_length_ratio 0.5)
				(max_length 1)
				(best_width_ratio 1)
				(max_width 2)
				(curved_edges yes)
				(filter_ratio 0.9)
				(enabled no)
				(allow_two_segments yes)
				(prefer_zone_connections no)
			)
		)
		(pad "68" smd rect
			(at -7.654757 -1.7)
			(size 0.35 3)
			(layers "B.Cu" "B.Mask")
			(net 11 "unconnected-(J1-SUSCLK-Pad68)")
			(pinfunction "SUSCLK")
			(pintype "passive+no_connect")
			(teardrops
				(best_length_ratio 0.5)
				(max_length 1)
				(best_width_ratio 1)
				(max_width 2)
				(curved_edges yes)
				(filter_ratio 0.9)
				(enabled no)
				(allow_two_segments yes)
				(prefer_zone_connections no)
			)
		)
		(pad "69" smd rect
			(at -7.9 -1.45)
			(size 0.35 2.5)
			(layers "F.Cu" "F.Mask")
			(net 33 "unconnected-(J1-PEDET-Pad69)")
			(pinfunction "PEDET")
			(pintype "passive+no_connect")
			(teardrops
				(best_length_ratio 0.5)
				(max_length 1)
				(best_width_ratio 1)
				(max_width 2)
				(curved_edges yes)
				(filter_ratio 0.9)
				(enabled no)
				(allow_two_segments yes)
				(prefer_zone_connections no)
			)
		)
		(pad "70" smd rect
			(at -8.154757 -1.7)
			(size 0.35 3)
			(layers "B.Cu" "B.Mask")
			(net 56 "Net-(C1-Pad2)")
			(pinfunction "3.3V")
			(pintype "passive")
			(teardrops
				(best_length_ratio 0.5)
				(max_length 1)
				(best_width_ratio 1)
				(max_width 2)
				(curved_edges yes)
				(filter_ratio 0.9)
				(enabled no)
				(allow_two_segments yes)
				(prefer_zone_connections no)
			)
		)
		(pad "71" smd rect
			(at -8.4 -1.45)
			(size 0.35 2.5)
			(layers "F.Cu" "F.Mask")
			(net 1 "GND")
			(pinfunction "GND")
			(pintype "passive")
			(teardrops
				(best_length_ratio 0.5)
				(max_length 1)
				(best_width_ratio 1)
				(max_width 2)
				(curved_edges yes)
				(filter_ratio 0.9)
				(enabled no)
				(allow_two_segments yes)
				(prefer_zone_connections no)
			)
		)
		(pad "72" smd rect
			(at -8.654757 -1.7)
			(size 0.35 3)
			(layers "B.Cu" "B.Mask")
			(net 56 "Net-(C1-Pad2)")
			(pinfunction "3.3V")
			(pintype "passive")
			(teardrops
				(best_length_ratio 0.5)
				(max_length 1)
				(best_width_ratio 1)
				(max_width 2)
				(curved_edges yes)
				(filter_ratio 0.9)
				(enabled no)
				(allow_two_segments yes)
				(prefer_zone_connections no)
			)
		)
		(pad "73" smd rect
			(at -8.9 -1.45)
			(size 0.35 2.5)
			(layers "F.Cu" "F.Mask")
			(net 1 "GND")
			(pinfunction "GND")
			(pintype "passive")
			(teardrops
				(best_length_ratio 0.5)
				(max_length 1)
				(best_width_ratio 1)
				(max_width 2)
				(curved_edges yes)
				(filter_ratio 0.9)
				(enabled no)
				(allow_two_segments yes)
				(prefer_zone_connections no)
			)
		)
		(pad "74" smd rect
			(at -9.154757 -1.7)
			(size 0.35 3)
			(layers "B.Cu" "B.Mask")
			(net 56 "Net-(C1-Pad2)")
			(pinfunction "3.3V")
			(pintype "passive")
			(teardrops
				(best_length_ratio 0.5)
				(max_length 1)
				(best_width_ratio 1)
				(max_width 2)
				(curved_edges yes)
				(filter_ratio 0.9)
				(enabled no)
				(allow_two_segments yes)
				(prefer_zone_connections no)
			)
		)
		(pad "75" smd rect
			(at -9.404757 -1.45)
			(size 0.35 2.5)
			(layers "F.Cu" "F.Mask")
			(net 1 "GND")
			(pinfunction "GND")
			(pintype "passive")
			(teardrops
				(best_length_ratio 0.5)
				(max_length 1)
				(best_width_ratio 1)
				(max_width 2)
				(curved_edges yes)
				(filter_ratio 0.9)
				(enabled no)
				(allow_two_segments yes)
				(prefer_zone_connections no)
			)
		)
	)
	(footprint "antmicro-footprints:Amphenol_G14A421211112HR"
		(locked yes)
		(layer "F.Cu")
		(at 146.017041 98.587904)
		(property "Reference" "J2"
			(at 4.592959 0.202096 0)
			(unlocked yes)
			(layer "F.SilkS")
			(effects
				(font
					(size 0.7 0.7)
					(thickness 0.15)
				)
				(justify left bottom)
			)
		)
		(property "Value" "OCuLink_x4_Amphenol_G14A421211112HR"
			(at 0 6.385 0)
			(unlocked yes)
			(layer "F.Fab")
			(effects
				(font
					(size 0.7 0.7)
					(thickness 0.15)
				)
				(justify left bottom)
			)
		)
		(property "Datasheet" "https://cdn.amphenol-cs.com/media/wysiwyg/files/drawing/g14a421x1bxxxhr.pdf"
			(at 0 0 0)
			(layer "F.Fab")
			(hide yes)
			(effects
				(font
					(size 1.27 1.27)
					(thickness 0.15)
				)
			)
		)
		(property "Description" "I/O Connectors OCulink, Receptacle, 0.5mm pitch, 4X, R/A SMT with shell leg SMT type, 30U\" gold plating, LCP, black, T&R packing"
			(at 0 0 0)
			(layer "F.Fab")
			(hide yes)
			(effects
				(font
					(size 1.27 1.27)
					(thickness 0.15)
				)
			)
		)
		(property "Manufacturer" "Amphenol"
			(at 0 0 0)
			(unlocked yes)
			(layer "F.Fab")
			(hide yes)
			(effects
				(font
					(size 1 1)
					(thickness 0.15)
				)
			)
		)
		(property "MPN" "G14A421211112HR"
			(at 0 0 0)
			(unlocked yes)
			(layer "F.Fab")
			(hide yes)
			(effects
				(font
					(size 1 1)
					(thickness 0.15)
				)
			)
		)
		(property "Author" "Antmicro"
			(at 0 0 0)
			(unlocked yes)
			(layer "F.Fab")
			(hide yes)
			(effects
				(font
					(size 1 1)
					(thickness 0.15)
				)
			)
		)
		(property "License" "Apache-2.0"
			(at 0 0 0)
			(unlocked yes)
			(layer "F.Fab")
			(hide yes)
			(effects
				(font
					(size 1 1)
					(thickness 0.15)
				)
			)
		)
		(sheetname "/")
		(sheetfile "antmicro-m2-oculink-adapter-hw.kicad_sch")
		(solder_paste_margin -0.06)
		(attr smd)
		(fp_line
			(start -6.8 -0.4)
			(end -6.8 -3)
			(stroke
				(width 0.1)
				(type default)
			)
			(layer "F.SilkS")
		)
		(fp_line
			(start 6.8 -3)
			(end 6.8 -0.4)
			(stroke
				(width 0.1)
				(type default)
			)
			(layer "F.SilkS")
		)
		(fp_circle
			(center -5.3 -5.52)
			(end -5.25 -5.52)
			(stroke
				(width 0.15)
				(type solid)
			)
			(fill yes)
			(layer "F.SilkS")
		)
		(fp_rect
			(start -8.22 -5.22)
			(end 8.22 4.94)
			(stroke
				(width 0.05)
				(type solid)
			)
			(fill no)
			(layer "F.CrtYd")
		)
		(fp_line
			(start 7 3.065)
			(end -7 3.065)
			(stroke
				(width 0.1)
				(type default)
			)
			(layer "F.Fab")
		)
		(fp_text user "Author: Antmicro"
			(at -8.22 11.085 0)
			(layer "F.Fab")
			(effects
				(font
					(size 0.7 0.7)
					(thickness 0.15)
				)
				(justify left bottom)
			)
		)
		(fp_text user "License: Apache-2.0"
			(at -8.22 12.285 0)
			(layer "F.Fab")
			(effects
				(font
					(size 0.7 0.7)
					(thickness 0.15)
				)
				(justify left bottom)
			)
		)
		(fp_text user "PCB EDGE"
			(at 2.8 2.95 0)
			(unlocked yes)
			(layer "F.Fab")
			(effects
				(font
					(size 0.5 0.5)
					(thickness 0.125)
				)
				(justify left bottom)
			)
		)
		(fp_text user "${REFERENCE}"
			(at -8.22 9.885 0)
			(unlocked yes)
			(layer "F.Fab")
			(effects
				(font
					(size 0.7 0.7)
					(thickness 0.15)
				)
				(justify left bottom)
			)
		)
		(pad "" np_thru_hole circle
			(at -5.42 -1.395 90)
			(size 1 1)
			(drill 1)
			(layers "F&B.Cu" "*.Mask")
		)
		(pad "" np_thru_hole circle
			(at 5.95 -1.395 90)
			(size 1 1)
			(drill 1)
			(layers "F&B.Cu" "*.Mask")
		)
		(pad "A1" smd roundrect
			(at -4.75 -2.115 90)
			(size 0.91 0.28)
			(layers "F.Cu" "F.Mask" "F.Paste")
			(roundrect_rratio 0.5)
			(net 17 "+3V3")
			(pinfunction "V_{ACT}_RX_3V3")
			(pintype "power_in")
		)
		(pad "A2" smd roundrect
			(at -4.25 -2.115 90)
			(size 0.91 0.28)
			(layers "F.Cu" "F.Mask" "F.Paste")
			(roundrect_rratio 0.5)
			(net 1 "GND")
			(pinfunction "GND")
			(pintype "passive")
		)
		(pad "A3" smd roundrect
			(at -3.75 -2.115 90)
			(size 0.91 0.28)
			(layers "F.Cu" "F.Mask" "F.Paste")
			(roundrect_rratio 0.5)
			(net 26 "/PCIe_{x4}.RX0+")
			(pinfunction "PER0+")
			(pintype "output")
		)
		(pad "A4" smd roundrect
			(at -3.25 -2.115 90)
			(size 0.91 0.28)
			(layers "F.Cu" "F.Mask" "F.Paste")
			(roundrect_rratio 0.5)
			(net 7 "/PCIe_{x4}.RX0-")
			(pinfunction "PER0-")
			(pintype "output")
		)
		(pad "A5" smd roundrect
			(at -2.75 -2.115 90)
			(size 0.91 0.28)
			(layers "F.Cu" "F.Mask" "F.Paste")
			(roundrect_rratio 0.5)
			(net 1 "GND")
			(pinfunction "GND")
			(pintype "passive")
		)
		(pad "A6" smd roundrect
			(at -2.25 -2.115 90)
			(size 0.91 0.28)
			(layers "F.Cu" "F.Mask" "F.Paste")
			(roundrect_rratio 0.5)
			(net 16 "/PCIe_{x4}.RX1+")
			(pinfunction "PER1+")
			(pintype "output")
		)
		(pad "A7" smd roundrect
			(at -1.75 -2.115 90)
			(size 0.91 0.28)
			(layers "F.Cu" "F.Mask" "F.Paste")
			(roundrect_rratio 0.5)
			(net 27 "/PCIe_{x4}.RX1-")
			(pinfunction "PER1-")
			(pintype "output")
		)
		(pad "A8" smd roundrect
			(at -1.25 -2.115 90)
			(size 0.91 0.28)
			(layers "F.Cu" "F.Mask" "F.Paste")
			(roundrect_rratio 0.5)
			(net 1 "GND")
			(pinfunction "GND")
			(pintype "passive")
		)
		(pad "A9" smd roundrect
			(at -0.75 -2.115 90)
			(size 0.91 0.28)
			(layers "F.Cu" "F.Mask" "F.Paste")
			(roundrect_rratio 0.5)
			(net 52 "unconnected-(J2-NC-PadA9)")
			(pinfunction "NC")
			(pintype "no_connect")
		)
		(pad "A10" smd roundrect
			(at -0.25 -2.115 90)
			(size 0.91 0.28)
			(layers "F.Cu" "F.Mask" "F.Paste")
			(roundrect_rratio 0.5)
			(net 24 "/~{WAKEC}")
			(pinfunction "~{CWAKE}")
			(pintype "bidirectional")
		)
		(pad "A11" smd roundrect
			(at 0.25 -2.115 90)
			(size 0.91 0.28)
			(layers "F.Cu" "F.Mask" "F.Paste")
			(roundrect_rratio 0.5)
			(net 1 "GND")
			(pinfunction "GND")
			(pintype "passive")
		)
		(pad "A12" smd roundrect
			(at 0.75 -2.115 90)
			(size 0.91 0.28)
			(layers "F.Cu" "F.Mask" "F.Paste")
			(roundrect_rratio 0.5)
			(net 13 "/PCIe_{REF0}_R.CK+")
			(pinfunction "VSP1")
			(pintype "bidirectional")
		)
		(pad "A13" smd roundrect
			(at 1.25 -2.115 90)
			(size 0.91 0.28)
			(layers "F.Cu" "F.Mask" "F.Paste")
			(roundrect_rratio 0.5)
			(net 12 "/PCIe_{REF0}_R.CK-")
			(pinfunction "VSP2")
			(pintype "bidirectional")
		)
		(pad "A14" smd roundrect
			(at 1.75 -2.115 90)
			(size 0.91 0.28)
			(layers "F.Cu" "F.Mask" "F.Paste")
			(roundrect_rratio 0.5)
			(net 1 "GND")
			(pinfunction "GND")
			(pintype "passive")
		)
		(pad "A15" smd roundrect
			(at 2.25 -2.115 90)
			(size 0.91 0.28)
			(layers "F.Cu" "F.Mask" "F.Paste")
			(roundrect_rratio 0.5)
			(net 4 "/PCIe_{x4}.RX2+")
			(pinfunction "PER2+")
			(pintype "output")
		)
		(pad "A16" smd roundrect
			(at 2.75 -2.115 90)
			(size 0.91 0.28)
			(layers "F.Cu" "F.Mask" "F.Paste")
			(roundrect_rratio 0.5)
			(net 14 "/PCIe_{x4}.RX2-")
			(pinfunction "PER2-")
			(pintype "output")
		)
		(pad "A17" smd roundrect
			(at 3.25 -2.115 90)
			(size 0.91 0.28)
			(layers "F.Cu" "F.Mask" "F.Paste")
			(roundrect_rratio 0.5)
			(net 1 "GND")
			(pinfunction "GND")
			(pintype "passive")
		)
		(pad "A18" smd roundrect
			(at 3.75 -2.115 90)
			(size 0.91 0.28)
			(layers "F.Cu" "F.Mask" "F.Paste")
			(roundrect_rratio 0.5)
			(net 9 "/PCIe_{x4}.RX3+")
			(pinfunction "PER3+")
			(pintype "output")
		)
		(pad "A19" smd roundrect
			(at 4.25 -2.115 90)
			(size 0.91 0.28)
			(layers "F.Cu" "F.Mask" "F.Paste")
			(roundrect_rratio 0.5)
			(net 6 "/PCIe_{x4}.RX3-")
			(pinfunction "PER3-")
			(pintype "output")
		)
		(pad "A20" smd roundrect
			(at 4.75 -2.115 90)
			(size 0.91 0.28)
			(layers "F.Cu" "F.Mask" "F.Paste")
			(roundrect_rratio 0.5)
			(net 1 "GND")
			(pinfunction "GND")
			(pintype "passive")
		)
		(pad "A21" smd roundrect
			(at 5.25 -2.115 90)
			(size 0.91 0.28)
			(layers "F.Cu" "F.Mask" "F.Paste")
			(roundrect_rratio 0.5)
			(net 50 "Net-(J2-5V-PadA21)")
			(pinfunction "5V")
			(pintype "passive")
		)
		(pad "B1" smd roundrect
			(at -5.25 -4.305 90)
			(size 0.91 0.28)
			(layers "F.Cu" "F.Mask" "F.Paste")
			(roundrect_rratio 0.5)
			(net 50 "Net-(J2-5V-PadA21)")
			(pinfunction "5V")
			(pintype "passive")
		)
		(pad "B2" smd roundrect
			(at -4.75 -4.305 90)
			(size 0.91 0.28)
			(layers "F.Cu" "F.Mask" "F.Paste")
			(roundrect_rratio 0.5)
			(net 1 "GND")
			(pinfunction "GND")
			(pintype "passive")
		)
		(pad "B3" smd roundrect
			(at -4.25 -4.305 90)
			(size 0.91 0.28)
			(layers "F.Cu" "F.Mask" "F.Paste")
			(roundrect_rratio 0.5)
			(net 25 "/PCIe_{x4}.TX0+")
			(pinfunction "PET0+")
			(pintype "input")
		)
		(pad "B4" smd roundrect
			(at -3.75 -4.305 90)
			(size 0.91 0.28)
			(layers "F.Cu" "F.Mask" "F.Paste")
			(roundrect_rratio 0.5)
			(net 15 "/PCIe_{x4}.TX0-")
			(pinfunction "PET0-")
			(pintype "input")
		)
		(pad "B5" smd roundrect
			(at -3.25 -4.305 90)
			(size 0.91 0.28)
			(layers "F.Cu" "F.Mask" "F.Paste")
			(roundrect_rratio 0.5)
			(net 1 "GND")
			(pinfunction "GND")
			(pintype "passive")
		)
		(pad "B6" smd roundrect
			(at -2.75 -4.305 90)
			(size 0.91 0.28)
			(layers "F.Cu" "F.Mask" "F.Paste")
			(roundrect_rratio 0.5)
			(net 3 "/PCIe_{x4}.TX1+")
			(pinfunction "PET1+")
			(pintype "input")
		)
		(pad "B7" smd roundrect
			(at -2.25 -4.305 90)
			(size 0.91 0.28)
			(layers "F.Cu" "F.Mask" "F.Paste")
			(roundrect_rratio 0.5)
			(net 8 "/PCIe_{x4}.TX1-")
			(pinfunction "PET1-")
			(pintype "input")
		)
		(pad "B8" smd roundrect
			(at -1.75 -4.305 90)
			(size 0.91 0.28)
			(layers "F.Cu" "F.Mask" "F.Paste")
			(roundrect_rratio 0.5)
			(net 1 "GND")
			(pinfunction "GND")
			(pintype "passive")
		)
		(pad "B9" smd roundrect
			(at -1.25 -4.305 90)
			(size 0.91 0.28)
			(layers "F.Cu" "F.Mask" "F.Paste")
			(roundrect_rratio 0.5)
			(net 53 "unconnected-(J2-SCL-PadB9)")
			(pinfunction "SCL")
			(pintype "bidirectional+no_connect")
		)
		(pad "B10" smd roundrect
			(at -0.75 -4.305 90)
			(size 0.91 0.28)
			(layers "F.Cu" "F.Mask" "F.Paste")
			(roundrect_rratio 0.5)
			(net 51 "/~{WAKE_C}_alt")
			(pinfunction "SDA")
			(pintype "bidirectional")
		)
		(pad "B11" smd roundrect
			(at -0.25 -4.305 90)
			(size 0.91 0.28)
			(layers "F.Cu" "F.Mask" "F.Paste")
			(roundrect_rratio 0.5)
			(net 1 "GND")
			(pinfunction "GND")
			(pintype "passive")
		)
		(pad "B12" smd roundrect
			(at 0.25 -4.305 90)
			(size 0.91 0.28)
			(layers "F.Cu" "F.Mask" "F.Paste")
			(roundrect_rratio 0.5)
			(net 23 "/~{PERSTC}")
			(pinfunction "~{PERST}")
			(pintype "bidirectional")
		)
		(pad "B13" smd roundrect
			(at 0.75 -4.305 90)
			(size 0.91 0.28)
			(layers "F.Cu" "F.Mask" "F.Paste")
			(roundrect_rratio 0.5)
			(net 54 "/~{CPRSNT}")
			(pinfunction "~{CPRSNT}")
			(pintype "bidirectional")
		)
		(pad "B14" smd roundrect
			(at 1.25 -4.305 90)
			(size 0.91 0.28)
			(layers "F.Cu" "F.Mask" "F.Paste")
			(roundrect_rratio 0.5)
			(net 1 "GND")
			(pinfunction "GND")
			(pintype "passive")
		)
		(pad "B15" smd roundrect
			(at 1.75 -4.305 90)
			(size 0.91 0.28)
			(layers "F.Cu" "F.Mask" "F.Paste")
			(roundrect_rratio 0.5)
			(net 5 "/PCIe_{x4}.TX2+")
			(pinfunction "PET2+")
			(pintype "input")
		)
		(pad "B16" smd roundrect
			(at 2.25 -4.305 90)
			(size 0.91 0.28)
			(layers "F.Cu" "F.Mask" "F.Paste")
			(roundrect_rratio 0.5)
			(net 10 "/PCIe_{x4}.TX2-")
			(pinfunction "PET2-")
			(pintype "input")
		)
		(pad "B17" smd roundrect
			(at 2.75 -4.305 90)
			(size 0.91 0.28)
			(layers "F.Cu" "F.Mask" "F.Paste")
			(roundrect_rratio 0.5)
			(net 1 "GND")
			(pinfunction "GND")
			(pintype "passive")
		)
		(pad "B18" smd roundrect
			(at 3.25 -4.305 90)
			(size 0.91 0.28)
			(layers "F.Cu" "F.Mask" "F.Paste")
			(roundrect_rratio 0.5)
			(net 2 "/PCIe_{x4}.TX3+")
			(pinfunction "PET3+")
			(pintype "input")
		)
		(pad "B19" smd roundrect
			(at 3.75 -4.305 90)
			(size 0.91 0.28)
			(layers "F.Cu" "F.Mask" "F.Paste")
			(roundrect_rratio 0.5)
			(net 21 "/PCIe_{x4}.TX3-")
			(pinfunction "PET3-")
			(pintype "input")
		)
		(pad "B20" smd roundrect
			(at 4.25 -4.305 90)
			(size 0.91 0.28)
			(layers "F.Cu" "F.Mask" "F.Paste")
			(roundrect_rratio 0.5)
			(net 1 "GND")
			(pinfunction "GND")
			(pintype "passive")
		)
		(pad "B21" smd roundrect
			(at 4.75 -4.305 90)
			(size 0.91 0.28)
			(layers "F.Cu" "F.Mask" "F.Paste")
			(roundrect_rratio 0.5)
			(net 57 "Net-(J2-V_{ACT}_TX_3V3)")
			(pinfunction "V_{ACT}_TX_3V3")
			(pintype "power_in")
		)
		(pad "SH" smd roundrect
			(at -6.91 -3.915 90)
			(size 1.38 1.81)
			(layers "F.Cu" "F.Mask" "F.Paste")
			(roundrect_rratio 0.1)
			(net 1 "GND")
			(pinfunction "SH")
			(pintype "passive")
		)
		(pad "SH" smd roundrect
			(at -6.91 0.805 90)
			(size 1.81 1.8)
			(layers "F.Cu" "F.Mask" "F.Paste")
			(roundrect_rratio 0.1)
			(net 1 "GND")
			(pinfunction "SH")
			(pintype "passive")
		)
		(pad "SH" smd roundrect
			(at 6.91 -3.915 90)
			(size 1.38 1.81)
			(layers "F.Cu" "F.Mask" "F.Paste")
			(roundrect_rratio 0.1)
			(net 1 "GND")
			(pinfunction "SH")
			(pintype "passive")
		)
		(pad "SH" smd roundrect
			(at 6.91 0.805 90)
			(size 1.81 1.8)
			(layers "F.Cu" "F.Mask" "F.Paste")
			(roundrect_rratio 0.1)
			(net 1 "GND")
			(pinfunction "SH")
			(pintype "passive")
		)
	)
	(footprint "antmicro-footprints:R_0201"
		(layer "F.Cu")
		(at 146.08 92.63 -90)
		(descr "Resistor SMD 0201")
		(tags "resistor SMD 0201")
		(property "Reference" "R10"
			(at -1.14 0.44 180)
			(layer "F.SilkS")
			(effects
				(font
					(size 0.7 0.7)
					(thickness 0.15)
				)
				(justify right top)
			)
		)
		(property "Value" "R_0R_0201"
			(at 0 1.25 90)
			(layer "F.Fab")
			(effects
				(font
					(size 0.7 0.7)
					(thickness 0.15)
				)
				(justify right top)
			)
		)
		(property "Datasheet" "https://www.bourns.com/docs/product-datasheets/cr.pdf"
			(at 0 0 90)
			(layer "F.Fab")
			(hide yes)
			(effects
				(font
					(size 1.27 1.27)
					(thickness 0.15)
				)
			)
		)
		(property "Description" "SMD Chip Resistor"
			(at 0 0 90)
			(layer "F.Fab")
			(hide yes)
			(effects
				(font
					(size 1.27 1.27)
					(thickness 0.15)
				)
			)
		)
		(property "MPN" "CR0201-FX-0R00GLF"
			(at 0 0 270)
			(unlocked yes)
			(layer "F.Fab")
			(hide yes)
			(effects
				(font
					(size 1 1)
					(thickness 0.15)
				)
			)
		)
		(property "Manufacturer" "Bourns"
			(at 0 0 270)
			(unlocked yes)
			(layer "F.Fab")
			(hide yes)
			(effects
				(font
					(size 1 1)
					(thickness 0.15)
				)
			)
		)
		(property "License" "Apache-2.0"
			(at 0 0 270)
			(unlocked yes)
			(layer "F.Fab")
			(hide yes)
			(effects
				(font
					(size 1 1)
					(thickness 0.15)
				)
			)
		)
		(property "Author" "Antmicro"
			(at 0 0 270)
			(unlocked yes)
			(layer "F.Fab")
			(hide yes)
			(effects
				(font
					(size 1 1)
					(thickness 0.15)
				)
			)
		)
		(property "Val" "0R"
			(at 0 0 270)
			(unlocked yes)
			(layer "F.Fab")
			(hide yes)
			(effects
				(font
					(size 1 1)
					(thickness 0.15)
				)
			)
		)
		(property "Tolerance" "1%"
			(at 0 0 270)
			(unlocked yes)
			(layer "F.Fab")
			(hide yes)
			(effects
				(font
					(size 1 1)
					(thickness 0.15)
				)
			)
		)
		(sheetname "/")
		(sheetfile "antmicro-m2-oculink-adapter-hw.kicad_sch")
		(attr smd)
		(fp_rect
			(start -0.7 -0.35)
			(end 0.7 0.35)
			(stroke
				(width 0.05)
				(type default)
			)
			(fill no)
			(layer "F.CrtYd")
		)
		(fp_rect
			(start -0.3 -0.15)
			(end 0.298 0.148)
			(stroke
				(width 0.15)
				(type solid)
			)
			(fill no)
			(layer "F.Fab")
		)
		(fp_text user "License: Apache-2.0"
			(at -0.71 4.25 90)
			(layer "F.Fab")
			(effects
				(font
					(size 0.7 0.7)
					(thickness 0.15)
				)
				(justify right top)
			)
		)
		(fp_text user "Author: Antmicro"
			(at -0.71 5.25 90)
			(layer "F.Fab")
			(effects
				(font
					(size 0.7 0.7)
					(thickness 0.15)
				)
				(justify right top)
			)
		)
		(fp_text user "${REFERENCE}"
			(at -0.71 3.25 90)
			(layer "F.Fab")
			(effects
				(font
					(size 0.7 0.7)
					(thickness 0.15)
				)
				(justify right top)
			)
		)
		(pad "" smd roundrect
			(at -0.346 0 270)
			(size 0.318 0.36)
			(layers "F.Paste")
			(roundrect_rratio 0.25)
		)
		(pad "" smd roundrect
			(at 0.344 0 270)
			(size 0.318 0.36)
			(layers "F.Paste")
			(roundrect_rratio 0.25)
		)
		(pad "1" smd roundrect
			(at -0.32 0 270)
			(size 0.46 0.4)
			(layers "F.Cu" "F.Mask")
			(roundrect_rratio 0.25)
			(net 55 "/~{PERST}")
			(pintype "passive")
		)
		(pad "2" smd roundrect
			(at 0.32 0 270)
			(size 0.46 0.4)
			(layers "F.Cu" "F.Mask")
			(roundrect_rratio 0.25)
			(net 23 "/~{PERSTC}")
			(pintype "passive")
		)
	)
	(footprint "antmicro-footprints:R_0402_1005Metric"
		(layer "F.Cu")
		(at 151.84 91.17 180)
		(descr "Resistor SMD 0402")
		(tags "resistor SMD 0402")
		(property "Reference" "R12"
			(at -3.61 0.47 0)
			(layer "F.SilkS")
			(effects
				(font
					(size 0.7 0.7)
					(thickness 0.15)
				)
				(justify right top)
			)
		)
		(property "Value" "R_0R_0402"
			(at -1.011843 1.772047 0)
			(layer "F.Fab")
			(effects
				(font
					(size 0.7 0.7)
					(thickness 0.15)
				)
				(justify right top)
			)
		)
		(property "Datasheet" "https://industrial.panasonic.com/cdbs/www-data/pdf/RDA0000/AOA0000C301.pdf"
			(at 0 0 0)
			(layer "F.Fab")
			(hide yes)
			(effects
				(font
					(size 1.27 1.27)
					(thickness 0.15)
				)
			)
		)
		(property "Description" "SMD Chip Resistor, Jumper, 0 ohm, 100 mW, 0402 [1005 Metric], Thick Film, General Purpose"
			(at 0 0 0)
			(layer "F.Fab")
			(hide yes)
			(effects
				(font
					(size 1.27 1.27)
					(thickness 0.15)
				)
			)
		)
		(property "MPN" "ERJ2GE0R00X"
			(at 0 0 180)
			(unlocked yes)
			(layer "F.Fab")
			(hide yes)
			(effects
				(font
					(size 1 1)
					(thickness 0.15)
				)
			)
		)
		(property "Manufacturer" "Panasonic"
			(at 0 0 180)
			(unlocked yes)
			(layer "F.Fab")
			(hide yes)
			(effects
				(font
					(size 1 1)
					(thickness 0.15)
				)
			)
		)
		(property "License" "Apache-2.0"
			(at 0 0 180)
			(unlocked yes)
			(layer "F.Fab")
			(hide yes)
			(effects
				(font
					(size 1 1)
					(thickness 0.15)
				)
			)
		)
		(property "Author" "Antmicro"
			(at 0 0 180)
			(unlocked yes)
			(layer "F.Fab")
			(hide yes)
			(effects
				(font
					(size 1 1)
					(thickness 0.15)
				)
			)
		)
		(property "Val" "0R"
			(at 0 0 180)
			(unlocked yes)
			(layer "F.Fab")
			(hide yes)
			(effects
				(font
					(size 1 1)
					(thickness 0.15)
				)
			)
		)
		(property "Tolerance" ""
			(at 0 0 180)
			(unlocked yes)
			(layer "F.Fab")
			(hide yes)
			(effects
				(font
					(size 1 1)
					(thickness 0.15)
				)
			)
		)
		(property "Current" "1A"
			(at 0 0 180)
			(unlocked yes)
			(layer "F.Fab")
			(hide yes)
			(effects
				(font
					(size 1 1)
					(thickness 0.15)
				)
			)
		)
		(sheetname "/")
		(sheetfile "antmicro-m2-oculink-adapter-hw.kicad_sch")
		(attr smd dnp)
		(fp_rect
			(start -0.925 -0.47)
			(end 0.925 0.47)
			(stroke
				(width 0.05)
				(type default)
			)
			(fill no)
			(layer "F.CrtYd")
		)
		(fp_rect
			(start -0.5 -0.25)
			(end 0.5 0.25)
			(stroke
				(width 0.15)
				(type solid)
			)
			(fill no)
			(layer "F.Fab")
		)
		(fp_text user "Author: Antmicro"
			(at -0.95 4.169 0)
			(layer "F.Fab")
			(effects
				(font
					(size 0.7 0.7)
					(thickness 0.15)
				)
				(justify right top)
			)
		)
		(fp_text user "License: Apache-2.0"
			(at -0.95 5.169 0)
			(layer "F.Fab")
			(effects
				(font
					(size 0.7 0.7)
					(thickness 0.15)
				)
				(justify right top)
			)
		)
		(fp_text user "${REFERENCE}"
			(at -0.95 3.168 0)
			(layer "F.Fab")
			(effects
				(font
					(size 0.7 0.7)
					(thickness 0.15)
				)
				(justify right top)
			)
		)
		(pad "1" smd roundrect
			(at -0.48 0 180)
			(size 0.59 0.64)
			(layers "F.Cu" "F.Mask" "F.Paste")
			(roundrect_rratio 0.25)
			(net 50 "Net-(J2-5V-PadA21)")
			(pintype "passive")
		)
		(pad "2" smd roundrect
			(at 0.48 0 180)
			(size 0.59 0.64)
			(layers "F.Cu" "F.Mask" "F.Paste")
			(roundrect_rratio 0.25)
			(net 50 "Net-(J2-5V-PadA21)")
			(pintype "passive")
		)
	)
	(footprint "antmicro-footprints:R_0402_1005Metric"
		(layer "F.Cu")
		(at 151.839541 92.222904 180)
		(descr "Resistor SMD 0402")
		(tags "resistor SMD 0402")
		(property "Reference" "R7"
			(at -1.430459 -0.437096 180)
			(layer "F.SilkS")
			(effects
				(font
					(size 0.7 0.7)
					(thickness 0.15)
				)
				(justify left bottom)
			)
		)
		(property "Value" "R_0R_0402"
			(at -1.011843 1.772047 180)
			(layer "F.Fab")
			(effects
				(font
					(size 0.7 0.7)
					(thickness 0.15)
				)
				(justify left bottom)
			)
		)
		(property "Datasheet" "https://industrial.panasonic.com/cdbs/www-data/pdf/RDA0000/AOA0000C301.pdf"
			(at 0 0 180)
			(layer "F.Fab")
			(hide yes)
			(effects
				(font
					(size 1.27 1.27)
					(thickness 0.15)
				)
			)
		)
		(property "Description" "SMD Chip Resistor, Jumper, 0 ohm, 100 mW, 0402 [1005 Metric], Thick Film, General Purpose"
			(at 0 0 180)
			(layer "F.Fab")
			(hide yes)
			(effects
				(font
					(size 1.27 1.27)
					(thickness 0.15)
				)
			)
		)
		(property "MPN" "ERJ2GE0R00X"
			(at 0 0 180)
			(unlocked yes)
			(layer "F.Fab")
			(hide yes)
			(effects
				(font
					(size 1 1)
					(thickness 0.15)
				)
			)
		)
		(property "Manufacturer" "Panasonic"
			(at 0 0 180)
			(unlocked yes)
			(layer "F.Fab")
			(hide yes)
			(effects
				(font
					(size 1 1)
					(thickness 0.15)
				)
			)
		)
		(property "License" "Apache-2.0"
			(at 0 0 180)
			(unlocked yes)
			(layer "F.Fab")
			(hide yes)
			(effects
				(font
					(size 1 1)
					(thickness 0.15)
				)
			)
		)
		(property "Author" "Antmicro"
			(at 0 0 180)
			(unlocked yes)
			(layer "F.Fab")
			(hide yes)
			(effects
				(font
					(size 1 1)
					(thickness 0.15)
				)
			)
		)
		(property "Val" "0R"
			(at 0 0 180)
			(unlocked yes)
			(layer "F.Fab")
			(hide yes)
			(effects
				(font
					(size 1 1)
					(thickness 0.15)
				)
			)
		)
		(property "Tolerance" ""
			(at 0 0 180)
			(unlocked yes)
			(layer "F.Fab")
			(hide yes)
			(effects
				(font
					(size 1 1)
					(thickness 0.15)
				)
			)
		)
		(property "Current" "1A"
			(at 0 0 180)
			(unlocked yes)
			(layer "F.Fab")
			(hide yes)
			(effects
				(font
					(size 1 1)
					(thickness 0.15)
				)
			)
		)
		(sheetname "/")
		(sheetfile "antmicro-m2-oculink-adapter-hw.kicad_sch")
		(attr smd)
		(fp_rect
			(start -0.925 -0.47)
			(end 0.925 0.47)
			(stroke
				(width 0.05)
				(type default)
			)
			(fill no)
			(layer "F.CrtYd")
		)
		(fp_rect
			(start -0.5 -0.25)
			(end 0.5 0.25)
			(stroke
				(width 0.15)
				(type solid)
			)
			(fill no)
			(layer "F.Fab")
		)
		(fp_text user "${REFERENCE}"
			(at -0.95 3.168 180)
			(layer "F.Fab")
			(effects
				(font
					(size 0.7 0.7)
					(thickness 0.15)
				)
				(justify left bottom)
			)
		)
		(fp_text user "License: Apache-2.0"
			(at 0.16 9.529 180)
			(layer "F.Fab")
			(effects
				(font
					(size 0.7 0.7)
					(thickness 0.15)
				)
				(justify left bottom)
			)
		)
		(fp_text user "Author: Antmicro"
			(at -0.95 4.169 180)
			(layer "F.Fab")
			(effects
				(font
					(size 0.7 0.7)
					(thickness 0.15)
				)
				(justify left bottom)
			)
		)
		(pad "1" smd roundrect
			(at -0.48 0 180)
			(size 0.59 0.64)
			(layers "F.Cu" "F.Mask" "F.Paste")
			(roundrect_rratio 0.25)
			(net 56 "Net-(C1-Pad2)")
			(pintype "passive")
		)
		(pad "2" smd roundrect
			(at 0.48 0 180)
			(size 0.59 0.64)
			(layers "F.Cu" "F.Mask" "F.Paste")
			(roundrect_rratio 0.25)
			(net 57 "Net-(J2-V_{ACT}_TX_3V3)")
			(pintype "passive")
		)
	)
	(footprint "antmicro-footprints:R_0201"
		(layer "F.Cu")
		(at 146.82 92.63 -90)
		(descr "Resistor SMD 0201")
		(tags "resistor SMD 0201")
		(property "Reference" "R13"
			(at -1.14 -2.44 180)
			(layer "F.SilkS")
			(effects
				(font
					(size 0.7 0.7)
					(thickness 0.15)
				)
				(justify right top)
			)
		)
		(property "Value" "R_0R_0201"
			(at 0 1.25 90)
			(layer "F.Fab")
			(effects
				(font
					(size 0.7 0.7)
					(thickness 0.15)
				)
				(justify right top)
			)
		)
		(property "Datasheet" "https://www.bourns.com/docs/product-datasheets/cr.pdf"
			(at 0 0 90)
			(layer "F.Fab")
			(hide yes)
			(effects
				(font
					(size 1.27 1.27)
					(thickness 0.15)
				)
			)
		)
		(property "Description" "SMD Chip Resistor"
			(at 0 0 90)
			(layer "F.Fab")
			(hide yes)
			(effects
				(font
					(size 1.27 1.27)
					(thickness 0.15)
				)
			)
		)
		(property "MPN" "CR0201-FX-0R00GLF"
			(at 0 0 270)
			(unlocked yes)
			(layer "F.Fab")
			(hide yes)
			(effects
				(font
					(size 1 1)
					(thickness 0.15)
				)
			)
		)
		(property "Manufacturer" "Bourns"
			(at 0 0 270)
			(unlocked yes)
			(layer "F.Fab")
			(hide yes)
			(effects
				(font
					(size 1 1)
					(thickness 0.15)
				)
			)
		)
		(property "License" "Apache-2.0"
			(at 0 0 270)
			(unlocked yes)
			(layer "F.Fab")
			(hide yes)
			(effects
				(font
					(size 1 1)
					(thickness 0.15)
				)
			)
		)
		(property "Author" "Antmicro"
			(at 0 0 270)
			(unlocked yes)
			(layer "F.Fab")
			(hide yes)
			(effects
				(font
					(size 1 1)
					(thickness 0.15)
				)
			)
		)
		(property "Val" "0R"
			(at 0 0 270)
			(unlocked yes)
			(layer "F.Fab")
			(hide yes)
			(effects
				(font
					(size 1 1)
					(thickness 0.15)
				)
			)
		)
		(property "Tolerance" "1%"
			(at 0 0 270)
			(unlocked yes)
			(layer "F.Fab")
			(hide yes)
			(effects
				(font
					(size 1 1)
					(thickness 0.15)
				)
			)
		)
		(sheetname "/")
		(sheetfile "antmicro-m2-oculink-adapter-hw.kicad_sch")
		(attr smd)
		(fp_rect
			(start -0.7 -0.35)
			(end 0.7 0.35)
			(stroke
				(width 0.05)
				(type default)
			)
			(fill no)
			(layer "F.CrtYd")
		)
		(fp_rect
			(start -0.3 -0.15)
			(end 0.298 0.148)
			(stroke
				(width 0.15)
				(type solid)
			)
			(fill no)
			(layer "F.Fab")
		)
		(fp_text user "License: Apache-2.0"
			(at -0.71 4.25 90)
			(layer "F.Fab")
			(effects
				(font
					(size 0.7 0.7)
					(thickness 0.15)
				)
				(justify right top)
			)
		)
		(fp_text user "Author: Antmicro"
			(at -0.71 5.25 90)
			(layer "F.Fab")
			(effects
				(font
					(size 0.7 0.7)
					(thickness 0.15)
				)
				(justify right top)
			)
		)
		(fp_text user "${REFERENCE}"
			(at -0.71 3.25 90)
			(layer "F.Fab")
			(effects
				(font
					(size 0.7 0.7)
					(thickness 0.15)
				)
				(justify right top)
			)
		)
		(pad "" smd roundrect
			(at -0.346 0 270)
			(size 0.318 0.36)
			(layers "F.Paste")
			(roundrect_rratio 0.25)
		)
		(pad "" smd roundrect
			(at 0.344 0 270)
			(size 0.318 0.36)
			(layers "F.Paste")
			(roundrect_rratio 0.25)
		)
		(pad "1" smd roundrect
			(at -0.32 0 270)
			(size 0.46 0.4)
			(layers "F.Cu" "F.Mask")
			(roundrect_rratio 0.25)
			(net 58 "Net-(R13-Pad1)")
			(pintype "passive")
		)
		(pad "2" smd roundrect
			(at 0.32 0 270)
			(size 0.46 0.4)
			(layers "F.Cu" "F.Mask")
			(roundrect_rratio 0.25)
			(net 54 "/~{CPRSNT}")
			(pintype "passive")
		)
	)
	(footprint "antmicro-footprints:TP_SMD_1.5mm"
		(layer "F.Cu")
		(at 136.65 101.4 180)
		(property "Reference" "TP1"
			(at 0.4045 3.53 90)
			(layer "F.SilkS")
			(effects
				(font
					(size 0.7 0.7)
					(thickness 0.15)
				)
				(justify right top)
			)
		)
		(property "Value" "TP_1.5mm_SMD"
			(at 0 1.7 0)
			(layer "F.Fab")
			(effects
				(font
					(size 0.7 0.7)
					(thickness 0.15)
				)
				(justify right top)
			)
		)
		(property "Description" "test point, SMT"
			(at 0 0 0)
			(layer "F.Fab")
			(hide yes)
			(effects
				(font
					(size 1.27 1.27)
					(thickness 0.15)
				)
			)
		)
		(property "MPN" ""
			(at 0 0 180)
			(unlocked yes)
			(layer "F.Fab")
			(hide yes)
			(effects
				(font
					(size 1 1)
					(thickness 0.15)
				)
			)
		)
		(property "Manufacturer" ""
			(at 0 0 180)
			(unlocked yes)
			(layer "F.Fab")
			(hide yes)
			(effects
				(font
					(size 1 1)
					(thickness 0.15)
				)
			)
		)
		(property "Author" "Antmicro"
			(at 0 0 180)
			(unlocked yes)
			(layer "F.Fab")
			(hide yes)
			(effects
				(font
					(size 1 1)
					(thickness 0.15)
				)
			)
		)
		(property "License" "Apache-2.0"
			(at 0 0 180)
			(unlocked yes)
			(layer "F.Fab")
			(hide yes)
			(effects
				(font
					(size 1 1)
					(thickness 0.15)
				)
			)
		)
		(sheetname "/")
		(sheetfile "antmicro-m2-oculink-adapter-hw.kicad_sch")
		(attr exclude_from_pos_files exclude_from_bom)
		(fp_circle
			(center 0 0)
			(end 0.85 0)
			(stroke
				(width 0.05)
				(type default)
			)
			(fill no)
			(layer "F.CrtYd")
		)
		(fp_text user "${REFERENCE}"
			(at -0.7 2.9 0)
			(layer "F.Fab")
			(effects
				(font
					(size 0.7 0.7)
					(thickness 0.15)
				)
				(justify right top)
			)
		)
		(fp_text user "Author: Antmicro"
			(at -0.7 4.101 0)
			(layer "F.Fab")
			(effects
				(font
					(size 0.7 0.7)
					(thickness 0.15)
				)
				(justify right top)
			)
		)
		(fp_text user "License: Apache-2.0"
			(at -0.7 5.301 0)
			(layer "F.Fab")
			(effects
				(font
					(size 0.7 0.7)
					(thickness 0.15)
				)
				(justify right top)
			)
		)
		(pad "1" smd circle
			(at 0 0 90)
			(size 1.5 1.5)
			(layers "F.Cu" "F.Mask")
			(net 55 "/~{PERST}")
			(pinfunction "1")
			(pintype "passive")
			(teardrops
				(best_length_ratio 0.5)
				(max_length 1)
				(best_width_ratio 1)
				(max_width 2)
				(curved_edges yes)
				(filter_ratio 0.9)
				(enabled no)
				(allow_two_segments yes)
				(prefer_zone_connections no)
			)
		)
	)
	(footprint "antmicro-footprints:TP_SMD_1.5mm"
		(layer "F.Cu")
		(at 136.62 103.63 180)
		(property "Reference" "TP2"
			(at -0.58 -2.95 90)
			(layer "F.SilkS")
			(effects
				(font
					(size 0.7 0.7)
					(thickness 0.15)
				)
				(justify left bottom)
			)
		)
		(property "Value" "TP_1.5mm_SMD"
			(at 0 1.7 0)
			(layer "F.Fab")
			(effects
				(font
					(size 0.7 0.7)
					(thickness 0.15)
				)
				(justify right top)
			)
		)
		(property "Description" "test point, SMT"
			(at 0 0 0)
			(layer "F.Fab")
			(hide yes)
			(effects
				(font
					(size 1.27 1.27)
					(thickness 0.15)
				)
			)
		)
		(property "MPN" ""
			(at 0 0 180)
			(unlocked yes)
			(layer "F.Fab")
			(hide yes)
			(effects
				(font
					(size 1 1)
					(thickness 0.15)
				)
			)
		)
		(property "Manufacturer" ""
			(at 0 0 180)
			(unlocked yes)
			(layer "F.Fab")
			(hide yes)
			(effects
				(font
					(size 1 1)
					(thickness 0.15)
				)
			)
		)
		(property "Author" "Antmicro"
			(at 0 0 180)
			(unlocked yes)
			(layer "F.Fab")
			(hide yes)
			(effects
				(font
					(size 1 1)
					(thickness 0.15)
				)
			)
		)
		(property "License" "Apache-2.0"
			(at 0 0 180)
			(unlocked yes)
			(layer "F.Fab")
			(hide yes)
			(effects
				(font
					(size 1 1)
					(thickness 0.15)
				)
			)
		)
		(sheetname "/")
		(sheetfile "antmicro-m2-oculink-adapter-hw.kicad_sch")
		(attr exclude_from_pos_files exclude_from_bom)
		(fp_circle
			(center 0 0)
			(end 0.85 0)
			(stroke
				(width 0.05)
				(type default)
			)
			(fill no)
			(layer "F.CrtYd")
		)
		(fp_text user "License: Apache-2.0"
			(at -0.7 5.301 0)
			(layer "F.Fab")
			(effects
				(font
					(size 0.7 0.7)
					(thickness 0.15)
				)
				(justify right top)
			)
		)
		(fp_text user "${REFERENCE}"
			(at -0.7 2.9 0)
			(layer "F.Fab")
			(effects
				(font
					(size 0.7 0.7)
					(thickness 0.15)
				)
				(justify right top)
			)
		)
		(fp_text user "Author: Antmicro"
			(at -0.7 4.101 0)
			(layer "F.Fab")
			(effects
				(font
					(size 0.7 0.7)
					(thickness 0.15)
				)
				(justify right top)
			)
		)
		(pad "1" smd circle
			(at 0 0 90)
			(size 1.5 1.5)
			(layers "F.Cu" "F.Mask")
			(net 37 "/~{WAKE}")
			(pinfunction "1")
			(pintype "passive")
			(teardrops
				(best_length_ratio 0.5)
				(max_length 1)
				(best_width_ratio 1)
				(max_width 2)
				(curved_edges yes)
				(filter_ratio 0.9)
				(enabled no)
				(allow_two_segments yes)
				(prefer_zone_connections no)
			)
		)
	)
	(footprint "antmicro-footprints:TP_SMD_1mm"
		(layer "F.Cu")
		(at 149.35 90.84)
		(property "Reference" "TP3"
			(at -0.42 -0.62 0)
			(layer "F.SilkS")
			(effects
				(font
					(size 0.7 0.7)
					(thickness 0.15)
				)
				(justify left bottom)
			)
		)
		(property "Value" "TP_1mm_SMD"
			(at 0 1.4 0)
			(layer "F.Fab")
			(effects
				(font
					(size 0.7 0.7)
					(thickness 0.15)
				)
				(justify left bottom)
			)
		)
		(property "Description" "Test point 1mm SMD"
			(at 0 0 0)
			(layer "F.Fab")
			(hide yes)
			(effects
				(font
					(size 1.27 1.27)
					(thickness 0.15)
				)
			)
		)
		(property "MPN" ""
			(at 0 0 0)
			(unlocked yes)
			(layer "F.Fab")
			(hide yes)
			(effects
				(font
					(size 1 1)
					(thickness 0.15)
				)
			)
		)
		(property "Manufacturer" ""
			(at 0 0 0)
			(unlocked yes)
			(layer "F.Fab")
			(hide yes)
			(effects
				(font
					(size 1 1)
					(thickness 0.15)
				)
			)
		)
		(property "Author" "Antmicro"
			(at 0 0 0)
			(unlocked yes)
			(layer "F.Fab")
			(hide yes)
			(effects
				(font
					(size 1 1)
					(thickness 0.15)
				)
			)
		)
		(property "License" "Apache-2.0"
			(at 0 0 0)
			(unlocked yes)
			(layer "F.Fab")
			(hide yes)
			(effects
				(font
					(size 1 1)
					(thickness 0.15)
				)
			)
		)
		(sheetname "/")
		(sheetfile "antmicro-m2-oculink-adapter-hw.kicad_sch")
		(attr exclude_from_pos_files exclude_from_bom)
		(fp_circle
			(center 0 0)
			(end 0.6 0)
			(stroke
				(width 0.05)
				(type default)
			)
			(fill no)
			(layer "F.CrtYd")
		)
		(fp_text user "${REFERENCE}"
			(at -0.5 2.8 0)
			(layer "F.Fab")
			(effects
				(font
					(size 0.7 0.7)
					(thickness 0.15)
				)
				(justify left bottom)
			)
		)
		(fp_text user "Author: Antmicro"
			(at -0.5 4 0)
			(layer "F.Fab")
			(effects
				(font
					(size 0.7 0.7)
					(thickness 0.15)
				)
				(justify left bottom)
			)
		)
		(fp_text user "License: Apache-2.0"
			(at -0.5 5.2 0)
			(layer "F.Fab")
			(effects
				(font
					(size 0.7 0.7)
					(thickness 0.15)
				)
				(justify left bottom)
			)
		)
		(pad "1" smd circle
			(at 0 0)
			(size 1 1)
			(layers "F.Cu" "F.Mask")
			(net 58 "Net-(R13-Pad1)")
			(pinfunction "1")
			(pintype "passive")
		)
	)
	(footprint "antmicro-footprints:C_0402_1005Metric"
		(layer "B.Cu")
		(at 139.45 97.42 90)
		(descr "Capacitor SMD 0402")
		(tags "capacitor SMD 0402")
		(property "Reference" "C3"
			(at -2.36 -0.37 270)
			(layer "B.SilkS")
			(effects
				(font
					(size 0.7 0.7)
					(thickness 0.15)
				)
				(justify right top mirror)
			)
		)
		(property "Value" "C_100n_16V_X7R_0402"
			(at -1.022927 -2.155213 90)
			(layer "B.Fab")
			(effects
				(font
					(size 0.7 0.7)
					(thickness 0.15)
				)
				(justify right top mirror)
			)
		)
		(property "Datasheet" "https://www.kemet.com/en/us/capacitors/product/C0402C104J4RAC7411.html"
			(at 0 0 90)
			(layer "B.Fab")
			(hide yes)
			(effects
				(font
					(size 1.27 1.27)
					(thickness 0.15)
				)
				(justify mirror)
			)
		)
		(property "Description" "SMD Multilayer Ceramic Capacitor, 100nF, 50V, 0402, ±5%, X7R"
			(at 0 0 90)
			(layer "B.Fab")
			(hide yes)
			(effects
				(font
					(size 1.27 1.27)
					(thickness 0.15)
				)
				(justify mirror)
			)
		)
		(property "MPN" "C0402C104J4RAC7411"
			(at 0 0 270)
			(unlocked yes)
			(layer "B.Fab")
			(hide yes)
			(effects
				(font
					(size 1 1)
					(thickness 0.15)
				)
				(justify mirror)
			)
		)
		(property "Val" "100n"
			(at 0 0 270)
			(unlocked yes)
			(layer "B.Fab")
			(hide yes)
			(effects
				(font
					(size 1 1)
					(thickness 0.15)
				)
				(justify mirror)
			)
		)
		(property "Voltage" "16V"
			(at 0 0 270)
			(unlocked yes)
			(layer "B.Fab")
			(hide yes)
			(effects
				(font
					(size 1 1)
					(thickness 0.15)
				)
				(justify mirror)
			)
		)
		(property "Dielectric" "X7R"
			(at 0 0 270)
			(unlocked yes)
			(layer "B.Fab")
			(hide yes)
			(effects
				(font
					(size 1 1)
					(thickness 0.15)
				)
				(justify mirror)
			)
		)
		(property "Manufacturer" "KEMET"
			(at 0 0 270)
			(unlocked yes)
			(layer "B.Fab")
			(hide yes)
			(effects
				(font
					(size 1 1)
					(thickness 0.15)
				)
				(justify mirror)
			)
		)
		(property "License" "Apache-2.0"
			(at 0 0 270)
			(unlocked yes)
			(layer "B.Fab")
			(hide yes)
			(effects
				(font
					(size 1 1)
					(thickness 0.15)
				)
				(justify mirror)
			)
		)
		(property "Author" "Antmicro"
			(at 0 0 270)
			(unlocked yes)
			(layer "B.Fab")
			(hide yes)
			(effects
				(font
					(size 1 1)
					(thickness 0.15)
				)
				(justify mirror)
			)
		)
		(sheetname "/")
		(sheetfile "antmicro-m2-oculink-adapter-hw.kicad_sch")
		(attr smd)
		(fp_rect
			(start -0.925 0.47)
			(end 0.925 -0.47)
			(stroke
				(width 0.05)
				(type default)
			)
			(fill no)
			(layer "B.CrtYd")
		)
		(fp_line
			(start 0.504 -0.248)
			(end -0.494 -0.248)
			(stroke
				(width 0.15)
				(type solid)
			)
			(layer "B.Fab")
		)
		(fp_line
			(start -0.494 -0.248)
			(end -0.494 0.25)
			(stroke
				(width 0.15)
				(type solid)
			)
			(layer "B.Fab")
		)
		(fp_line
			(start 0.504 0.25)
			(end 0.504 -0.248)
			(stroke
				(width 0.15)
				(type solid)
			)
			(layer "B.Fab")
		)
		(fp_line
			(start -0.494 0.25)
			(end 0.504 0.25)
			(stroke
				(width 0.15)
				(type solid)
			)
			(layer "B.Fab")
		)
		(fp_text user "${REFERENCE}"
			(at -0.939 -4.599 90)
			(layer "B.Fab")
			(effects
				(font
					(size 0.7 0.7)
					(thickness 0.15)
				)
				(justify right top mirror)
			)
		)
		(fp_text user "Author: Antmicro"
			(at -0.939 -3.399 90)
			(layer "B.Fab")
			(effects
				(font
					(size 0.7 0.7)
					(thickness 0.15)
				)
				(justify right top mirror)
			)
		)
		(fp_text user "License: Apache-2.0"
			(at -0.939 -5.799 90)
			(layer "B.Fab")
			(effects
				(font
					(size 0.7 0.7)
					(thickness 0.15)
				)
				(justify right top mirror)
			)
		)
		(pad "1" smd roundrect
			(at -0.48 0 90)
			(size 0.59 0.64)
			(layers "B.Cu" "B.Mask" "B.Paste")
			(roundrect_rratio 0.25)
			(net 1 "GND")
			(pintype "passive")
		)
		(pad "2" smd roundrect
			(at 0.48 0 90)
			(size 0.59 0.64)
			(layers "B.Cu" "B.Mask" "B.Paste")
			(roundrect_rratio 0.25)
			(net 17 "+3V3")
			(pintype "passive")
		)
	)
	(footprint "antmicro-footprints:R_0201"
		(layer "B.Cu")
		(at 146.64 95.02 90)
		(descr "Resistor SMD 0201")
		(tags "resistor SMD 0201")
		(property "Reference" "R6"
			(at -3.77 -0.05 270)
			(layer "B.SilkS")
			(effects
				(font
					(size 0.7 0.7)
					(thickness 0.15)
				)
				(justify right top mirror)
			)
		)
		(property "Value" "R_0R_0201"
			(at 0 -1.25 90)
			(layer "B.Fab")
			(effects
				(font
					(size 0.7 0.7)
					(thickness 0.15)
				)
				(justify right top mirror)
			)
		)
		(property "Datasheet" "https://www.bourns.com/docs/product-datasheets/cr.pdf"
			(at 0 0 90)
			(layer "B.Fab")
			(hide yes)
			(effects
				(font
					(size 1.27 1.27)
					(thickness 0.15)
				)
				(justify mirror)
			)
		)
		(property "Description" "SMD Chip Resistor"
			(at 0 0 90)
			(layer "B.Fab")
			(hide yes)
			(effects
				(font
					(size 1.27 1.27)
					(thickness 0.15)
				)
				(justify mirror)
			)
		)
		(property "MPN" "CR0201-FX-0R00GLF"
			(at 0 0 270)
			(unlocked yes)
			(layer "B.Fab")
			(hide yes)
			(effects
				(font
					(size 1 1)
					(thickness 0.15)
				)
				(justify mirror)
			)
		)
		(property "Manufacturer" "Bourns"
			(at 0 0 270)
			(unlocked yes)
			(layer "B.Fab")
			(hide yes)
			(effects
				(font
					(size 1 1)
					(thickness 0.15)
				)
				(justify mirror)
			)
		)
		(property "License" "Apache-2.0"
			(at 0 0 270)
			(unlocked yes)
			(layer "B.Fab")
			(hide yes)
			(effects
				(font
					(size 1 1)
					(thickness 0.15)
				)
				(justify mirror)
			)
		)
		(property "Author" "Antmicro"
			(at 0 0 270)
			(unlocked yes)
			(layer "B.Fab")
			(hide yes)
			(effects
				(font
					(size 1 1)
					(thickness 0.15)
				)
				(justify mirror)
			)
		)
		(property "Val" "0R"
			(at 0 0 270)
			(unlocked yes)
			(layer "B.Fab")
			(hide yes)
			(effects
				(font
					(size 1 1)
					(thickness 0.15)
				)
				(justify mirror)
			)
		)
		(property "Tolerance" "1%"
			(at 0 0 270)
			(unlocked yes)
			(layer "B.Fab")
			(hide yes)
			(effects
				(font
					(size 1 1)
					(thickness 0.15)
				)
				(justify mirror)
			)
		)
		(sheetname "/")
		(sheetfile "antmicro-m2-oculink-adapter-hw.kicad_sch")
		(attr smd)
		(fp_rect
			(start -0.7 0.35)
			(end 0.7 -0.35)
			(stroke
				(width 0.05)
				(type default)
			)
			(fill no)
			(layer "B.CrtYd")
		)
		(fp_rect
			(start -0.3 0.15)
			(end 0.298 -0.148)
			(stroke
				(width 0.15)
				(type solid)
			)
			(fill no)
			(layer "B.Fab")
		)
		(fp_text user "Author: Antmicro"
			(at -0.71 -5.25 90)
			(layer "B.Fab")
			(effects
				(font
					(size 0.7 0.7)
					(thickness 0.15)
				)
				(justify right top mirror)
			)
		)
		(fp_text user "License: Apache-2.0"
			(at -0.71 -4.25 90)
			(layer "B.Fab")
			(effects
				(font
					(size 0.7 0.7)
					(thickness 0.15)
				)
				(justify right top mirror)
			)
		)
		(fp_text user "${REFERENCE}"
			(at -0.71 -3.25 90)
			(layer "B.Fab")
			(effects
				(font
					(size 0.7 0.7)
					(thickness 0.15)
				)
				(justify right top mirror)
			)
		)
		(pad "" smd roundrect
			(at -0.346 0 90)
			(size 0.318 0.36)
			(layers "B.Paste")
			(roundrect_rratio 0.25)
		)
		(pad "" smd roundrect
			(at 0.344 0 90)
			(size 0.318 0.36)
			(layers "B.Paste")
			(roundrect_rratio 0.25)
		)
		(pad "1" smd roundrect
			(at -0.32 0 90)
			(size 0.46 0.4)
			(layers "B.Cu" "B.Mask")
			(roundrect_rratio 0.25)
			(net 12 "/PCIe_{REF0}_R.CK-")
			(pintype "passive")
		)
		(pad "2" smd roundrect
			(at 0.32 0 90)
			(size 0.46 0.4)
			(layers "B.Cu" "B.Mask")
			(roundrect_rratio 0.25)
			(net 38 "/PCIe_{REF0}.CK-")
			(pintype "passive")
		)
	)
	(footprint "antmicro-footprints:R_0201"
		(layer "B.Cu")
		(at 144.22 94.75 -90)
		(descr "Resistor SMD 0201")
		(tags "resistor SMD 0201")
		(property "Reference" "R9"
			(at 0.84 -0.45 90)
			(layer "B.SilkS")
			(effects
				(font
					(size 0.7 0.7)
					(thickness 0.15)
				)
				(justify left bottom mirror)
			)
		)
		(property "Value" "R_0R_0201"
			(at 0 -1.249999 90)
			(layer "B.Fab")
			(effects
				(font
					(size 0.7 0.7)
					(thickness 0.15)
				)
				(justify left bottom mirror)
			)
		)
		(property "Datasheet" "https://www.bourns.com/docs/product-datasheets/cr.pdf"
			(at 0 0 90)
			(layer "B.Fab")
			(hide yes)
			(effects
				(font
					(size 1.27 1.27)
					(thickness 0.15)
				)
				(justify mirror)
			)
		)
		(property "Description" "SMD Chip Resistor"
			(at 0 0 90)
			(layer "B.Fab")
			(hide yes)
			(effects
				(font
					(size 1.27 1.27)
					(thickness 0.15)
				)
				(justify mirror)
			)
		)
		(property "MPN" "CR0201-FX-0R00GLF"
			(at 0 0 90)
			(unlocked yes)
			(layer "B.Fab")
			(hide yes)
			(effects
				(font
					(size 1 1)
					(thickness 0.15)
				)
				(justify mirror)
			)
		)
		(property "Manufacturer" "Bourns"
			(at 0 0 90)
			(unlocked yes)
			(layer "B.Fab")
			(hide yes)
			(effects
				(font
					(size 1 1)
					(thickness 0.15)
				)
				(justify mirror)
			)
		)
		(property "License" "Apache-2.0"
			(at 0 0 90)
			(unlocked yes)
			(layer "B.Fab")
			(hide yes)
			(effects
				(font
					(size 1 1)
					(thickness 0.15)
				)
				(justify mirror)
			)
		)
		(property "Author" "Antmicro"
			(at 0 0 90)
			(unlocked yes)
			(layer "B.Fab")
			(hide yes)
			(effects
				(font
					(size 1 1)
					(thickness 0.15)
				)
				(justify mirror)
			)
		)
		(property "Val" "0R"
			(at 0 0 90)
			(unlocked yes)
			(layer "B.Fab")
			(hide yes)
			(effects
				(font
					(size 1 1)
					(thickness 0.15)
				)
				(justify mirror)
			)
		)
		(property "Tolerance" "1%"
			(at 0 0 90)
			(unlocked yes)
			(layer "B.Fab")
			(hide yes)
			(effects
				(font
					(size 1 1)
					(thickness 0.15)
				)
				(justify mirror)
			)
		)
		(sheetname "/")
		(sheetfile "antmicro-m2-oculink-adapter-hw.kicad_sch")
		(attr smd dnp)
		(fp_rect
			(start -0.7 0.35)
			(end 0.7 -0.35)
			(stroke
				(width 0.05)
				(type default)
			)
			(fill no)
			(layer "B.CrtYd")
		)
		(fp_rect
			(start -0.3 0.15)
			(end 0.298 -0.148)
			(stroke
				(width 0.15)
				(type solid)
			)
			(fill no)
			(layer "B.Fab")
		)
		(fp_text user "License: Apache-2.0"
			(at -0.71 -4.25 90)
			(layer "B.Fab")
			(effects
				(font
					(size 0.7 0.7)
					(thickness 0.15)
				)
				(justify left bottom mirror)
			)
		)
		(fp_text user "${REFERENCE}"
			(at -0.71 -3.25 90)
			(layer "B.Fab")
			(effects
				(font
					(size 0.7 0.7)
					(thickness 0.15)
				)
				(justify left bottom mirror)
			)
		)
		(fp_text user "Author: Antmicro"
			(at -0.71 -5.25 90)
			(layer "B.Fab")
			(effects
				(font
					(size 0.7 0.7)
					(thickness 0.15)
				)
				(justify left bottom mirror)
			)
		)
		(pad "" smd roundrect
			(at -0.346 0 270)
			(size 0.318 0.36)
			(layers "B.Paste")
			(roundrect_rratio 0.25)
		)
		(pad "" smd roundrect
			(at 0.344 0 270)
			(size 0.318 0.36)
			(layers "B.Paste")
			(roundrect_rratio 0.25)
		)
		(pad "1" smd roundrect
			(at -0.32 0 270)
			(size 0.46 0.4)
			(layers "B.Cu" "B.Mask")
			(roundrect_rratio 0.25)
			(net 24 "/~{WAKEC}")
			(pintype "passive")
		)
		(pad "2" smd roundrect
			(at 0.32 0 270)
			(size 0.46 0.4)
			(layers "B.Cu" "B.Mask")
			(roundrect_rratio 0.25)
			(net 51 "/~{WAKE_C}_alt")
			(pintype "passive")
		)
	)
	(footprint "antmicro-footprints:R_0201"
		(layer "B.Cu")
		(at 145.93 95.02 90)
		(descr "Resistor SMD 0201")
		(tags "resistor SMD 0201")
		(property "Reference" "R4"
			(at -3.75 -0.64 270)
			(layer "B.SilkS")
			(effects
				(font
					(size 0.7 0.7)
					(thickness 0.15)
				)
				(justify right top mirror)
			)
		)
		(property "Value" "R_0R_0201"
			(at 0 -1.25 90)
			(layer "B.Fab")
			(effects
				(font
					(size 0.7 0.7)
					(thickness 0.15)
				)
				(justify right top mirror)
			)
		)
		(property "Datasheet" "https://www.bourns.com/docs/product-datasheets/cr.pdf"
			(at 0 0 90)
			(layer "B.Fab")
			(hide yes)
			(effects
				(font
					(size 1.27 1.27)
					(thickness 0.15)
				)
				(justify mirror)
			)
		)
		(property "Description" "SMD Chip Resistor"
			(at 0 0 90)
			(layer "B.Fab")
			(hide yes)
			(effects
				(font
					(size 1.27 1.27)
					(thickness 0.15)
				)
				(justify mirror)
			)
		)
		(property "MPN" "CR0201-FX-0R00GLF"
			(at 0 0 270)
			(unlocked yes)
			(layer "B.Fab")
			(hide yes)
			(effects
				(font
					(size 1 1)
					(thickness 0.15)
				)
				(justify mirror)
			)
		)
		(property "Manufacturer" "Bourns"
			(at 0 0 270)
			(unlocked yes)
			(layer "B.Fab")
			(hide yes)
			(effects
				(font
					(size 1 1)
					(thickness 0.15)
				)
				(justify mirror)
			)
		)
		(property "License" "Apache-2.0"
			(at 0 0 270)
			(unlocked yes)
			(layer "B.Fab")
			(hide yes)
			(effects
				(font
					(size 1 1)
					(thickness 0.15)
				)
				(justify mirror)
			)
		)
		(property "Author" "Antmicro"
			(at 0 0 270)
			(unlocked yes)
			(layer "B.Fab")
			(hide yes)
			(effects
				(font
					(size 1 1)
					(thickness 0.15)
				)
				(justify mirror)
			)
		)
		(property "Val" "0R"
			(at 0 0 270)
			(unlocked yes)
			(layer "B.Fab")
			(hide yes)
			(effects
				(font
					(size 1 1)
					(thickness 0.15)
				)
				(justify mirror)
			)
		)
		(property "Tolerance" "1%"
			(at 0 0 270)
			(unlocked yes)
			(layer "B.Fab")
			(hide yes)
			(effects
				(font
					(size 1 1)
					(thickness 0.15)
				)
				(justify mirror)
			)
		)
		(sheetname "/")
		(sheetfile "antmicro-m2-oculink-adapter-hw.kicad_sch")
		(attr smd)
		(fp_rect
			(start -0.7 0.35)
			(end 0.7 -0.35)
			(stroke
				(width 0.05)
				(type default)
			)
			(fill no)
			(layer "B.CrtYd")
		)
		(fp_rect
			(start -0.3 0.15)
			(end 0.298 -0.148)
			(stroke
				(width 0.15)
				(type solid)
			)
			(fill no)
			(layer "B.Fab")
		)
		(fp_text user "${REFERENCE}"
			(at -0.71 -3.25 90)
			(layer "B.Fab")
			(effects
				(font
					(size 0.7 0.7)
					(thickness 0.15)
				)
				(justify right top mirror)
			)
		)
		(fp_text user "License: Apache-2.0"
			(at -0.71 -4.25 90)
			(layer "B.Fab")
			(effects
				(font
					(size 0.7 0.7)
					(thickness 0.15)
				)
				(justify right top mirror)
			)
		)
		(fp_text user "Author: Antmicro"
			(at -0.71 -5.25 90)
			(layer "B.Fab")
			(effects
				(font
					(size 0.7 0.7)
					(thickness 0.15)
				)
				(justify right top mirror)
			)
		)
		(pad "" smd roundrect
			(at -0.346 0 90)
			(size 0.318 0.36)
			(layers "B.Paste")
			(roundrect_rratio 0.25)
		)
		(pad "" smd roundrect
			(at 0.344 0 90)
			(size 0.318 0.36)
			(layers "B.Paste")
			(roundrect_rratio 0.25)
		)
		(pad "1" smd roundrect
			(at -0.32 0 90)
			(size 0.46 0.4)
			(layers "B.Cu" "B.Mask")
			(roundrect_rratio 0.25)
			(net 13 "/PCIe_{REF0}_R.CK+")
			(pintype "passive")
		)
		(pad "2" smd roundrect
			(at 0.32 0 90)
			(size 0.46 0.4)
			(layers "B.Cu" "B.Mask")
			(roundrect_rratio 0.25)
			(net 36 "/PCIe_{REF0}.CK+")
			(pintype "passive")
		)
	)
	(footprint "antmicro-footprints:R_0201"
		(layer "B.Cu")
		(at 145.93 94.38 90)
		(descr "Resistor SMD 0201")
		(tags "resistor SMD 0201")
		(property "Reference" "R3"
			(at -2.9 -0.64 270)
			(layer "B.SilkS")
			(effects
				(font
					(size 0.7 0.7)
					(thickness 0.15)
				)
				(justify right top mirror)
			)
		)
		(property "Value" "R_0R_0201"
			(at 0 -1.25 90)
			(layer "B.Fab")
			(effects
				(font
					(size 0.7 0.7)
					(thickness 0.15)
				)
				(justify right top mirror)
			)
		)
		(property "Datasheet" "https://www.bourns.com/docs/product-datasheets/cr.pdf"
			(at 0 0 90)
			(layer "B.Fab")
			(hide yes)
			(effects
				(font
					(size 1.27 1.27)
					(thickness 0.15)
				)
				(justify mirror)
			)
		)
		(property "Description" "SMD Chip Resistor"
			(at 0 0 90)
			(layer "B.Fab")
			(hide yes)
			(effects
				(font
					(size 1.27 1.27)
					(thickness 0.15)
				)
				(justify mirror)
			)
		)
		(property "MPN" "CR0201-FX-0R00GLF"
			(at 0 0 270)
			(unlocked yes)
			(layer "B.Fab")
			(hide yes)
			(effects
				(font
					(size 1 1)
					(thickness 0.15)
				)
				(justify mirror)
			)
		)
		(property "Manufacturer" "Bourns"
			(at 0 0 270)
			(unlocked yes)
			(layer "B.Fab")
			(hide yes)
			(effects
				(font
					(size 1 1)
					(thickness 0.15)
				)
				(justify mirror)
			)
		)
		(property "License" "Apache-2.0"
			(at 0 0 270)
			(unlocked yes)
			(layer "B.Fab")
			(hide yes)
			(effects
				(font
					(size 1 1)
					(thickness 0.15)
				)
				(justify mirror)
			)
		)
		(property "Author" "Antmicro"
			(at 0 0 270)
			(unlocked yes)
			(layer "B.Fab")
			(hide yes)
			(effects
				(font
					(size 1 1)
					(thickness 0.15)
				)
				(justify mirror)
			)
		)
		(property "Val" "0R"
			(at 0 0 270)
			(unlocked yes)
			(layer "B.Fab")
			(hide yes)
			(effects
				(font
					(size 1 1)
					(thickness 0.15)
				)
				(justify mirror)
			)
		)
		(property "Tolerance" "1%"
			(at 0 0 270)
			(unlocked yes)
			(layer "B.Fab")
			(hide yes)
			(effects
				(font
					(size 1 1)
					(thickness 0.15)
				)
				(justify mirror)
			)
		)
		(sheetname "/")
		(sheetfile "antmicro-m2-oculink-adapter-hw.kicad_sch")
		(attr smd dnp)
		(fp_rect
			(start -0.7 0.35)
			(end 0.7 -0.35)
			(stroke
				(width 0.05)
				(type default)
			)
			(fill no)
			(layer "B.CrtYd")
		)
		(fp_rect
			(start -0.3 0.15)
			(end 0.298 -0.148)
			(stroke
				(width 0.15)
				(type solid)
			)
			(fill no)
			(layer "B.Fab")
		)
		(fp_text user "${REFERENCE}"
			(at -0.71 -3.25 90)
			(layer "B.Fab")
			(effects
				(font
					(size 0.7 0.7)
					(thickness 0.15)
				)
				(justify right top mirror)
			)
		)
		(fp_text user "Author: Antmicro"
			(at -0.71 -5.25 90)
			(layer "B.Fab")
			(effects
				(font
					(size 0.7 0.7)
					(thickness 0.15)
				)
				(justify right top mirror)
			)
		)
		(fp_text user "License: Apache-2.0"
			(at -0.71 -4.25 90)
			(layer "B.Fab")
			(effects
				(font
					(size 0.7 0.7)
					(thickness 0.15)
				)
				(justify right top mirror)
			)
		)
		(pad "" smd roundrect
			(at -0.346 0 90)
			(size 0.318 0.36)
			(layers "B.Paste")
			(roundrect_rratio 0.25)
		)
		(pad "" smd roundrect
			(at 0.344 0 90)
			(size 0.318 0.36)
			(layers "B.Paste")
			(roundrect_rratio 0.25)
		)
		(pad "1" smd roundrect
			(at -0.32 0 90)
			(size 0.46 0.4)
			(layers "B.Cu" "B.Mask")
			(roundrect_rratio 0.25)
			(net 36 "/PCIe_{REF0}.CK+")
			(pintype "passive")
		)
		(pad "2" smd roundrect
			(at 0.32 0 90)
			(size 0.46 0.4)
			(layers "B.Cu" "B.Mask")
			(roundrect_rratio 0.25)
			(net 23 "/~{PERSTC}")
			(pintype "passive")
		)
	)
	(footprint "antmicro-footprints:R_0402_1005Metric"
		(layer "B.Cu")
		(at 151.83 90.09 180)
		(descr "Resistor SMD 0402")
		(tags "resistor SMD 0402")
		(property "Reference" "R8"
			(at -2.45 -0.41 0)
			(layer "B.SilkS")
			(effects
				(font
					(size 0.7 0.7)
					(thickness 0.15)
				)
				(justify left bottom mirror)
			)
		)
		(property "Value" "R_0R_0402"
			(at -1.011843 -1.772047 0)
			(layer "B.Fab")
			(effects
				(font
					(size 0.7 0.7)
					(thickness 0.15)
				)
				(justify left bottom mirror)
			)
		)
		(property "Datasheet" "https://industrial.panasonic.com/cdbs/www-data/pdf/RDA0000/AOA0000C301.pdf"
			(at 0 0 0)
			(layer "B.Fab")
			(hide yes)
			(effects
				(font
					(size 1.27 1.27)
					(thickness 0.15)
				)
				(justify mirror)
			)
		)
		(property "Description" "SMD Chip Resistor, Jumper, 0 ohm, 100 mW, 0402 [1005 Metric], Thick Film, General Purpose"
			(at 0 0 0)
			(layer "B.Fab")
			(hide yes)
			(effects
				(font
					(size 1.27 1.27)
					(thickness 0.15)
				)
				(justify mirror)
			)
		)
		(property "MPN" "ERJ2GE0R00X"
			(at 0 0 0)
			(unlocked yes)
			(layer "B.Fab")
			(hide yes)
			(effects
				(font
					(size 1 1)
					(thickness 0.15)
				)
				(justify mirror)
			)
		)
		(property "Manufacturer" "Panasonic"
			(at 0 0 0)
			(unlocked yes)
			(layer "B.Fab")
			(hide yes)
			(effects
				(font
					(size 1 1)
					(thickness 0.15)
				)
				(justify mirror)
			)
		)
		(property "License" "Apache-2.0"
			(at 0 0 0)
			(unlocked yes)
			(layer "B.Fab")
			(hide yes)
			(effects
				(font
					(size 1 1)
					(thickness 0.15)
				)
				(justify mirror)
			)
		)
		(property "Author" "Antmicro"
			(at 0 0 0)
			(unlocked yes)
			(layer "B.Fab")
			(hide yes)
			(effects
				(font
					(size 1 1)
					(thickness 0.15)
				)
				(justify mirror)
			)
		)
		(property "Val" "0R"
			(at 0 0 0)
			(unlocked yes)
			(layer "B.Fab")
			(hide yes)
			(effects
				(font
					(size 1 1)
					(thickness 0.15)
				)
				(justify mirror)
			)
		)
		(property "Tolerance" ""
			(at 0 0 0)
			(unlocked yes)
			(layer "B.Fab")
			(hide yes)
			(effects
				(font
					(size 1 1)
					(thickness 0.15)
				)
				(justify mirror)
			)
		)
		(property "Current" "1A"
			(at 0 0 0)
			(unlocked yes)
			(layer "B.Fab")
			(hide yes)
			(effects
				(font
					(size 1 1)
					(thickness 0.15)
				)
				(justify mirror)
			)
		)
		(sheetname "/")
		(sheetfile "antmicro-m2-oculink-adapter-hw.kicad_sch")
		(attr smd)
		(fp_rect
			(start -0.925 0.47)
			(end 0.925 -0.47)
			(stroke
				(width 0.05)
				(type default)
			)
			(fill no)
			(layer "B.CrtYd")
		)
		(fp_rect
			(start -0.5 0.25)
			(end 0.5 -0.25)
			(stroke
				(width 0.15)
				(type solid)
			)
			(fill no)
			(layer "B.Fab")
		)
		(fp_text user "${REFERENCE}"
			(at -0.95 -3.168 0)
			(layer "B.Fab")
			(effects
				(font
					(size 0.7 0.7)
					(thickness 0.15)
				)
				(justify left bottom mirror)
			)
		)
		(fp_text user "Author: Antmicro"
			(at -0.95 -4.169 0)
			(layer "B.Fab")
			(effects
				(font
					(size 0.7 0.7)
					(thickness 0.15)
				)
				(justify left bottom mirror)
			)
		)
		(fp_text user "License: Apache-2.0"
			(at -0.95 -5.169 0)
			(layer "B.Fab")
			(effects
				(font
					(size 0.7 0.7)
					(thickness 0.15)
				)
				(justify left bottom mirror)
			)
		)
		(pad "1" smd roundrect
			(at -0.48 0 180)
			(size 0.59 0.64)
			(layers "B.Cu" "B.Mask" "B.Paste")
			(roundrect_rratio 0.25)
			(net 56 "Net-(C1-Pad2)")
			(pintype "passive")
		)
		(pad "2" smd roundrect
			(at 0.48 0 180)
			(size 0.59 0.64)
			(layers "B.Cu" "B.Mask" "B.Paste")
			(roundrect_rratio 0.25)
			(net 17 "+3V3")
			(pintype "passive")
		)
	)
	(footprint "antmicro-footprints:C_0402_1005Metric"
		(layer "B.Cu")
		(at 151.47 95.09 90)
		(descr "Capacitor SMD 0402")
		(tags "capacitor SMD 0402")
		(property "Reference" "C4"
			(at 0.91 -0.33 90)
			(layer "B.SilkS")
			(effects
				(font
					(size 0.7 0.7)
					(thickness 0.15)
				)
				(justify right top mirror)
			)
		)
		(property "Value" "C_100n_16V_X7R_0402"
			(at -1.022927 -2.155213 90)
			(layer "B.Fab")
			(effects
				(font
					(size 0.7 0.7)
					(thickness 0.15)
				)
				(justify right top mirror)
			)
		)
		(property "Datasheet" "https://www.kemet.com/en/us/capacitors/product/C0402C104J4RAC7411.html"
			(at 0 0 90)
			(layer "B.Fab")
			(hide yes)
			(effects
				(font
					(size 1.27 1.27)
					(thickness 0.15)
				)
				(justify mirror)
			)
		)
		(property "Description" "SMD Multilayer Ceramic Capacitor, 100nF, 50V, 0402, ±5%, X7R"
			(at 0 0 90)
			(layer "B.Fab")
			(hide yes)
			(effects
				(font
					(size 1.27 1.27)
					(thickness 0.15)
				)
				(justify mirror)
			)
		)
		(property "MPN" "C0402C104J4RAC7411"
			(at 0 0 270)
			(unlocked yes)
			(layer "B.Fab")
			(hide yes)
			(effects
				(font
					(size 1 1)
					(thickness 0.15)
				)
				(justify mirror)
			)
		)
		(property "Val" "100n"
			(at 0 0 270)
			(unlocked yes)
			(layer "B.Fab")
			(hide yes)
			(effects
				(font
					(size 1 1)
					(thickness 0.15)
				)
				(justify mirror)
			)
		)
		(property "Voltage" "16V"
			(at 0 0 270)
			(unlocked yes)
			(layer "B.Fab")
			(hide yes)
			(effects
				(font
					(size 1 1)
					(thickness 0.15)
				)
				(justify mirror)
			)
		)
		(property "Dielectric" "X7R"
			(at 0 0 270)
			(unlocked yes)
			(layer "B.Fab")
			(hide yes)
			(effects
				(font
					(size 1 1)
					(thickness 0.15)
				)
				(justify mirror)
			)
		)
		(property "Manufacturer" "KEMET"
			(at 0 0 270)
			(unlocked yes)
			(layer "B.Fab")
			(hide yes)
			(effects
				(font
					(size 1 1)
					(thickness 0.15)
				)
				(justify mirror)
			)
		)
		(property "License" "Apache-2.0"
			(at 0 0 270)
			(unlocked yes)
			(layer "B.Fab")
			(hide yes)
			(effects
				(font
					(size 1 1)
					(thickness 0.15)
				)
				(justify mirror)
			)
		)
		(property "Author" "Antmicro"
			(at 0 0 270)
			(unlocked yes)
			(layer "B.Fab")
			(hide yes)
			(effects
				(font
					(size 1 1)
					(thickness 0.15)
				)
				(justify mirror)
			)
		)
		(sheetname "/")
		(sheetfile "antmicro-m2-oculink-adapter-hw.kicad_sch")
		(attr smd)
		(fp_rect
			(start -0.925 0.47)
			(end 0.925 -0.47)
			(stroke
				(width 0.05)
				(type default)
			)
			(fill no)
			(layer "B.CrtYd")
		)
		(fp_line
			(start 0.504 -0.248)
			(end -0.494 -0.248)
			(stroke
				(width 0.15)
				(type solid)
			)
			(layer "B.Fab")
		)
		(fp_line
			(start -0.494 -0.248)
			(end -0.494 0.25)
			(stroke
				(width 0.15)
				(type solid)
			)
			(layer "B.Fab")
		)
		(fp_line
			(start 0.504 0.25)
			(end 0.504 -0.248)
			(stroke
				(width 0.15)
				(type solid)
			)
			(layer "B.Fab")
		)
		(fp_line
			(start -0.494 0.25)
			(end 0.504 0.25)
			(stroke
				(width 0.15)
				(type solid)
			)
			(layer "B.Fab")
		)
		(fp_text user "${REFERENCE}"
			(at -0.939 -4.599 90)
			(layer "B.Fab")
			(effects
				(font
					(size 0.7 0.7)
					(thickness 0.15)
				)
				(justify right top mirror)
			)
		)
		(fp_text user "License: Apache-2.0"
			(at -0.939 -5.799 90)
			(layer "B.Fab")
			(effects
				(font
					(size 0.7 0.7)
					(thickness 0.15)
				)
				(justify right top mirror)
			)
		)
		(fp_text user "Author: Antmicro"
			(at -0.939 -3.399 90)
			(layer "B.Fab")
			(effects
				(font
					(size 0.7 0.7)
					(thickness 0.15)
				)
				(justify right top mirror)
			)
		)
		(pad "1" smd roundrect
			(at -0.48 0 90)
			(size 0.59 0.64)
			(layers "B.Cu" "B.Mask" "B.Paste")
			(roundrect_rratio 0.25)
			(net 1 "GND")
			(pintype "passive")
		)
		(pad "2" smd roundrect
			(at 0.48 0 90)
			(size 0.59 0.64)
			(layers "B.Cu" "B.Mask" "B.Paste")
			(roundrect_rratio 0.25)
			(net 57 "Net-(J2-V_{ACT}_TX_3V3)")
			(pintype "passive")
		)
	)
	(footprint "antmicro-footprints:C_0402_1005Metric"
		(layer "B.Cu")
		(at 156.29 124.22 90)
		(descr "Capacitor SMD 0402")
		(tags "capacitor SMD 0402")
		(property "Reference" "C1"
			(at 1.37 -0.33 90)
			(layer "B.SilkS")
			(effects
				(font
					(size 0.7 0.7)
					(thickness 0.15)
				)
				(justify right top mirror)
			)
		)
		(property "Value" "C_100n_16V_X7R_0402"
			(at -1.022927 -2.155213 90)
			(layer "B.Fab")
			(effects
				(font
					(size 0.7 0.7)
					(thickness 0.15)
				)
				(justify right top mirror)
			)
		)
		(property "Datasheet" "https://www.kemet.com/en/us/capacitors/product/C0402C104J4RAC7411.html"
			(at 0 0 90)
			(layer "B.Fab")
			(hide yes)
			(effects
				(font
					(size 1.27 1.27)
					(thickness 0.15)
				)
				(justify mirror)
			)
		)
		(property "Description" "SMD Multilayer Ceramic Capacitor, 100nF, 50V, 0402, ±5%, X7R"
			(at 0 0 90)
			(layer "B.Fab")
			(hide yes)
			(effects
				(font
					(size 1.27 1.27)
					(thickness 0.15)
				)
				(justify mirror)
			)
		)
		(property "MPN" "C0402C104J4RAC7411"
			(at 0 0 270)
			(unlocked yes)
			(layer "B.Fab")
			(hide yes)
			(effects
				(font
					(size 1 1)
					(thickness 0.15)
				)
				(justify mirror)
			)
		)
		(property "Val" "100n"
			(at 0 0 270)
			(unlocked yes)
			(layer "B.Fab")
			(hide yes)
			(effects
				(font
					(size 1 1)
					(thickness 0.15)
				)
				(justify mirror)
			)
		)
		(property "Voltage" "16V"
			(at 0 0 270)
			(unlocked yes)
			(layer "B.Fab")
			(hide yes)
			(effects
				(font
					(size 1 1)
					(thickness 0.15)
				)
				(justify mirror)
			)
		)
		(property "Dielectric" "X7R"
			(at 0 0 270)
			(unlocked yes)
			(layer "B.Fab")
			(hide yes)
			(effects
				(font
					(size 1 1)
					(thickness 0.15)
				)
				(justify mirror)
			)
		)
		(property "Manufacturer" "KEMET"
			(at 0 0 270)
			(unlocked yes)
			(layer "B.Fab")
			(hide yes)
			(effects
				(font
					(size 1 1)
					(thickness 0.15)
				)
				(justify mirror)
			)
		)
		(property "License" "Apache-2.0"
			(at 0 0 270)
			(unlocked yes)
			(layer "B.Fab")
			(hide yes)
			(effects
				(font
					(size 1 1)
					(thickness 0.15)
				)
				(justify mirror)
			)
		)
		(property "Author" "Antmicro"
			(at 0 0 270)
			(unlocked yes)
			(layer "B.Fab")
			(hide yes)
			(effects
				(font
					(size 1 1)
					(thickness 0.15)
				)
				(justify mirror)
			)
		)
		(sheetname "/")
		(sheetfile "antmicro-m2-oculink-adapter-hw.kicad_sch")
		(attr smd)
		(fp_rect
			(start -0.925 0.47)
			(end 0.925 -0.47)
			(stroke
				(width 0.05)
				(type default)
			)
			(fill no)
			(layer "B.CrtYd")
		)
		(fp_line
			(start 0.504 -0.248)
			(end -0.494 -0.248)
			(stroke
				(width 0.15)
				(type solid)
			)
			(layer "B.Fab")
		)
		(fp_line
			(start -0.494 -0.248)
			(end -0.494 0.25)
			(stroke
				(width 0.15)
				(type solid)
			)
			(layer "B.Fab")
		)
		(fp_line
			(start 0.504 0.25)
			(end 0.504 -0.248)
			(stroke
				(width 0.15)
				(type solid)
			)
			(layer "B.Fab")
		)
		(fp_line
			(start -0.494 0.25)
			(end 0.504 0.25)
			(stroke
				(width 0.15)
				(type solid)
			)
			(layer "B.Fab")
		)
		(fp_text user "License: Apache-2.0"
			(at -0.939 -5.799 90)
			(layer "B.Fab")
			(effects
				(font
					(size 0.7 0.7)
					(thickness 0.15)
				)
				(justify right top mirror)
			)
		)
		(fp_text user "Author: Antmicro"
			(at -0.939 -3.399 90)
			(layer "B.Fab")
			(effects
				(font
					(size 0.7 0.7)
					(thickness 0.15)
				)
				(justify right top mirror)
			)
		)
		(fp_text user "${REFERENCE}"
			(at -0.939 -4.599 90)
			(layer "B.Fab")
			(effects
				(font
					(size 0.7 0.7)
					(thickness 0.15)
				)
				(justify right top mirror)
			)
		)
		(pad "1" smd roundrect
			(at -0.48 0 90)
			(size 0.59 0.64)
			(layers "B.Cu" "B.Mask" "B.Paste")
			(roundrect_rratio 0.25)
			(net 1 "GND")
			(pintype "passive")
		)
		(pad "2" smd roundrect
			(at 0.48 0 90)
			(size 0.59 0.64)
			(layers "B.Cu" "B.Mask" "B.Paste")
			(roundrect_rratio 0.25)
			(net 56 "Net-(C1-Pad2)")
			(pintype "passive")
		)
	)
	(footprint "antmicro-footprints:R_0201"
		(layer "B.Cu")
		(at 145.61 95.34 180)
		(descr "Resistor SMD 0201")
		(tags "resistor SMD 0201")
		(property "Reference" "R2"
			(at 0.58 -3.068916 0)
			(layer "B.SilkS")
			(effects
				(font
					(size 0.7 0.7)
					(thickness 0.15)
				)
				(justify left bottom mirror)
			)
		)
		(property "Value" "R_0R_0201"
			(at 0 -1.25 0)
			(layer "B.Fab")
			(effects
				(font
					(size 0.7 0.7)
					(thickness 0.15)
				)
				(justify left bottom mirror)
			)
		)
		(property "Datasheet" "https://www.bourns.com/docs/product-datasheets/cr.pdf"
			(at 0 0 0)
			(layer "B.Fab")
			(hide yes)
			(effects
				(font
					(size 1.27 1.27)
					(thickness 0.15)
				)
				(justify mirror)
			)
		)
		(property "Description" "SMD Chip Resistor"
			(at 0 0 0)
			(layer "B.Fab")
			(hide yes)
			(effects
				(font
					(size 1.27 1.27)
					(thickness 0.15)
				)
				(justify mirror)
			)
		)
		(property "MPN" "CR0201-FX-0R00GLF"
			(at 0 0 0)
			(unlocked yes)
			(layer "B.Fab")
			(hide yes)
			(effects
				(font
					(size 1 1)
					(thickness 0.15)
				)
				(justify mirror)
			)
		)
		(property "Manufacturer" "Bourns"
			(at 0 0 0)
			(unlocked yes)
			(layer "B.Fab")
			(hide yes)
			(effects
				(font
					(size 1 1)
					(thickness 0.15)
				)
				(justify mirror)
			)
		)
		(property "License" "Apache-2.0"
			(at 0 0 0)
			(unlocked yes)
			(layer "B.Fab")
			(hide yes)
			(effects
				(font
					(size 1 1)
					(thickness 0.15)
				)
				(justify mirror)
			)
		)
		(property "Author" "Antmicro"
			(at 0 0 0)
			(unlocked yes)
			(layer "B.Fab")
			(hide yes)
			(effects
				(font
					(size 1 1)
					(thickness 0.15)
				)
				(justify mirror)
			)
		)
		(property "Val" "0R"
			(at 0 0 0)
			(unlocked yes)
			(layer "B.Fab")
			(hide yes)
			(effects
				(font
					(size 1 1)
					(thickness 0.15)
				)
				(justify mirror)
			)
		)
		(property "Tolerance" "1%"
			(at 0 0 0)
			(unlocked yes)
			(layer "B.Fab")
			(hide yes)
			(effects
				(font
					(size 1 1)
					(thickness 0.15)
				)
				(justify mirror)
			)
		)
		(sheetname "/")
		(sheetfile "antmicro-m2-oculink-adapter-hw.kicad_sch")
		(attr smd dnp)
		(fp_rect
			(start -0.7 0.35)
			(end 0.7 -0.35)
			(stroke
				(width 0.05)
				(type default)
			)
			(fill no)
			(layer "B.CrtYd")
		)
		(fp_rect
			(start -0.3 0.15)
			(end 0.298 -0.148)
			(stroke
				(width 0.15)
				(type solid)
			)
			(fill no)
			(layer "B.Fab")
		)
		(fp_text user "License: Apache-2.0"
			(at -0.71 -4.25 0)
			(layer "B.Fab")
			(effects
				(font
					(size 0.7 0.7)
					(thickness 0.15)
				)
				(justify left bottom mirror)
			)
		)
		(fp_text user "Author: Antmicro"
			(at -0.71 -5.25 0)
			(layer "B.Fab")
			(effects
				(font
					(size 0.7 0.7)
					(thickness 0.15)
				)
				(justify left bottom mirror)
			)
		)
		(fp_text user "${REFERENCE}"
			(at -0.71 -3.25 0)
			(layer "B.Fab")
			(effects
				(font
					(size 0.7 0.7)
					(thickness 0.15)
				)
				(justify left bottom mirror)
			)
		)
		(pad "" smd roundrect
			(at -0.346 0 180)
			(size 0.318 0.36)
			(layers "B.Paste")
			(roundrect_rratio 0.25)
		)
		(pad "" smd roundrect
			(at 0.344 0 180)
			(size 0.318 0.36)
			(layers "B.Paste")
			(roundrect_rratio 0.25)
		)
		(pad "1" smd roundrect
			(at -0.32 0 180)
			(size 0.46 0.4)
			(layers "B.Cu" "B.Mask")
			(roundrect_rratio 0.25)
			(net 13 "/PCIe_{REF0}_R.CK+")
			(pintype "passive")
		)
		(pad "2" smd roundrect
			(at 0.32 0 180)
			(size 0.46 0.4)
			(layers "B.Cu" "B.Mask")
			(roundrect_rratio 0.25)
			(net 55 "/~{PERST}")
			(pintype "passive")
		)
	)
	(footprint "antmicro-footprints:R_0201"
		(layer "B.Cu")
		(at 146.64 94.38 90)
		(descr "Resistor SMD 0201")
		(tags "resistor SMD 0201")
		(property "Reference" "R5"
			(at -2.9 -0.05 90)
			(layer "B.SilkS")
			(effects
				(font
					(size 0.7 0.7)
					(thickness 0.15)
				)
				(justify right top mirror)
			)
		)
		(property "Value" "R_0R_0201"
			(at 0 -1.25 90)
			(layer "B.Fab")
			(effects
				(font
					(size 0.7 0.7)
					(thickness 0.15)
				)
				(justify right top mirror)
			)
		)
		(property "Datasheet" "https://www.bourns.com/docs/product-datasheets/cr.pdf"
			(at 0 0 90)
			(layer "B.Fab")
			(hide yes)
			(effects
				(font
					(size 1.27 1.27)
					(thickness 0.15)
				)
				(justify mirror)
			)
		)
		(property "Description" "SMD Chip Resistor"
			(at 0 0 90)
			(layer "B.Fab")
			(hide yes)
			(effects
				(font
					(size 1.27 1.27)
					(thickness 0.15)
				)
				(justify mirror)
			)
		)
		(property "MPN" "CR0201-FX-0R00GLF"
			(at 0 0 270)
			(unlocked yes)
			(layer "B.Fab")
			(hide yes)
			(effects
				(font
					(size 1 1)
					(thickness 0.15)
				)
				(justify mirror)
			)
		)
		(property "Manufacturer" "Bourns"
			(at 0 0 270)
			(unlocked yes)
			(layer "B.Fab")
			(hide yes)
			(effects
				(font
					(size 1 1)
					(thickness 0.15)
				)
				(justify mirror)
			)
		)
		(property "License" "Apache-2.0"
			(at 0 0 270)
			(unlocked yes)
			(layer "B.Fab")
			(hide yes)
			(effects
				(font
					(size 1 1)
					(thickness 0.15)
				)
				(justify mirror)
			)
		)
		(property "Author" "Antmicro"
			(at 0 0 270)
			(unlocked yes)
			(layer "B.Fab")
			(hide yes)
			(effects
				(font
					(size 1 1)
					(thickness 0.15)
				)
				(justify mirror)
			)
		)
		(property "Val" "0R"
			(at 0 0 270)
			(unlocked yes)
			(layer "B.Fab")
			(hide yes)
			(effects
				(font
					(size 1 1)
					(thickness 0.15)
				)
				(justify mirror)
			)
		)
		(property "Tolerance" "1%"
			(at 0 0 270)
			(unlocked yes)
			(layer "B.Fab")
			(hide yes)
			(effects
				(font
					(size 1 1)
					(thickness 0.15)
				)
				(justify mirror)
			)
		)
		(sheetname "/")
		(sheetfile "antmicro-m2-oculink-adapter-hw.kicad_sch")
		(attr smd dnp)
		(fp_rect
			(start -0.7 0.35)
			(end 0.7 -0.35)
			(stroke
				(width 0.05)
				(type default)
			)
			(fill no)
			(layer "B.CrtYd")
		)
		(fp_rect
			(start -0.3 0.15)
			(end 0.298 -0.148)
			(stroke
				(width 0.15)
				(type solid)
			)
			(fill no)
			(layer "B.Fab")
		)
		(fp_text user "License: Apache-2.0"
			(at -0.71 -4.25 90)
			(layer "B.Fab")
			(effects
				(font
					(size 0.7 0.7)
					(thickness 0.15)
				)
				(justify right top mirror)
			)
		)
		(fp_text user "${REFERENCE}"
			(at -0.71 -3.25 90)
			(layer "B.Fab")
			(effects
				(font
					(size 0.7 0.7)
					(thickness 0.15)
				)
				(justify right top mirror)
			)
		)
		(fp_text user "Author: Antmicro"
			(at -0.71 -5.25 90)
			(layer "B.Fab")
			(effects
				(font
					(size 0.7 0.7)
					(thickness 0.15)
				)
				(justify right top mirror)
			)
		)
		(pad "" smd roundrect
			(at -0.346 0 90)
			(size 0.318 0.36)
			(layers "B.Paste")
			(roundrect_rratio 0.25)
		)
		(pad "" smd roundrect
			(at 0.344 0 90)
			(size 0.318 0.36)
			(layers "B.Paste")
			(roundrect_rratio 0.25)
		)
		(pad "1" smd roundrect
			(at -0.32 0 90)
			(size 0.46 0.4)
			(layers "B.Cu" "B.Mask")
			(roundrect_rratio 0.25)
			(net 38 "/PCIe_{REF0}.CK-")
			(pintype "passive")
		)
		(pad "2" smd roundrect
			(at 0.32 0 90)
			(size 0.46 0.4)
			(layers "B.Cu" "B.Mask")
			(roundrect_rratio 0.25)
			(net 54 "/~{CPRSNT}")
			(pintype "passive")
		)
	)
	(gr_line
		(start 140.63 130.6)
		(end 140.63 127.75)
		(stroke
			(width 0.05)
			(type default)
		)
		(layer "Edge.Cuts")
	)
	(gr_line
		(start 144.267041 50.6)
		(end 143.35 50.6)
		(stroke
			(width 0.05)
			(type default)
		)
		(layer "Edge.Cuts")
	)
	(gr_circle
		(center 139.21 70.6)
		(end 139.36 70.6)
		(stroke
			(width 0.1)
			(type solid)
		)
		(fill no)
		(layer "Edge.Cuts")
	)
	(gr_circle
		(center 155.9 70.6)
		(end 155.75 70.6)
		(stroke
			(width 0.1)
			(type solid)
		)
		(fill no)
		(layer "Edge.Cuts")
	)
	(gr_circle
		(center 149.41 70.6)
		(end 149.26 70.6)
		(stroke
			(width 0.1)
			(type solid)
		)
		(fill no)
		(layer "Edge.Cuts")
	)
	(gr_circle
		(center 155.2 70.6)
		(end 155.05 70.6)
		(stroke
			(width 0.1)
			(type solid)
		)
		(fill no)
		(layer "Edge.Cuts")
	)
	(gr_circle
		(center 138.51 70.6)
		(end 138.66 70.6)
		(stroke
			(width 0.1)
			(type solid)
		)
		(fill no)
		(layer "Edge.Cuts")
	)
	(gr_line
		(start 139.43 130.6)
		(end 136.23 130.6)
		(stroke
			(width 0.05)
			(type default)
		)
		(layer "Edge.Cuts")
	)
	(gr_line
		(start 156.08315 130.6)
		(end 140.63 130.6)
		(stroke
			(width 0.05)
			(type default)
		)
		(layer "Edge.Cuts")
	)
	(gr_circle
		(center 137.11 70.6)
		(end 137.26 70.6)
		(stroke
			(width 0.1)
			(type solid)
		)
		(fill no)
		(layer "Edge.Cuts")
	)
	(gr_circle
		(center 141.41 70.6)
		(end 141.56 70.6)
		(stroke
			(width 0.1)
			(type solid)
		)
		(fill no)
		(layer "Edge.Cuts")
	)
	(gr_circle
		(center 153.8 70.6)
		(end 153.65 70.6)
		(stroke
			(width 0.1)
			(type solid)
		)
		(fill no)
		(layer "Edge.Cuts")
	)
	(gr_line
		(start 136.226447 127.080403)
		(end 136.23 127.2)
		(stroke
			(width 0.05)
			(type default)
		)
		(layer "Edge.Cuts")
	)
	(gr_line
		(start 135.15 50.603553)
		(end 143.35 50.6)
		(stroke
			(width 0.05)
			(type default)
		)
		(locked yes)
		(layer "Edge.Cuts")
	)
	(gr_circle
		(center 151.65 70.6)
		(end 151.5 70.6)
		(stroke
			(width 0.1)
			(type solid)
		)
		(fill no)
		(layer "Edge.Cuts")
	)
	(gr_circle
		(center 135.71 70.6)
		(end 135.86 70.6)
		(stroke
			(width 0.1)
			(type solid)
		)
		(fill no)
		(layer "Edge.Cuts")
	)
	(gr_line
		(start 148.2 50.6)
		(end 147.767041 50.6)
		(stroke
			(width 0.05)
			(type default)
		)
		(layer "Edge.Cuts")
	)
	(gr_circle
		(center 153.1 70.6)
		(end 152.95 70.6)
		(stroke
			(width 0.1)
			(type solid)
		)
		(fill no)
		(layer "Edge.Cuts")
	)
	(gr_arc
		(start 139.43 127.7)
		(mid 140.03 127.1)
		(end 140.63 127.7)
		(stroke
			(width 0.05)
			(type default)
		)
		(layer "Edge.Cuts")
	)
	(gr_line
		(start 157.15 50.603553)
		(end 149.01 50.6)
		(stroke
			(width 0.05)
			(type default)
		)
		(locked yes)
		(layer "Edge.Cuts")
	)
	(gr_arc
		(start 135.73 126.603553)
		(mid 136.074182 126.742076)
		(end 136.226447 127.080403)
		(stroke
			(width 0.05)
			(type default)
		)
		(layer "Edge.Cuts")
	)
	(gr_line
		(start 157.15 50.603553)
		(end 157.15 126.603553)
		(stroke
			(width 0.05)
			(type solid)
		)
		(locked yes)
		(layer "Edge.Cuts")
	)
	(gr_line
		(start 139.43 127.7)
		(end 139.43 130.6)
		(stroke
			(width 0.05)
			(type default)
		)
		(layer "Edge.Cuts")
	)
	(gr_circle
		(center 150.15 70.6)
		(end 150 70.6)
		(stroke
			(width 0.1)
			(type solid)
		)
		(fill no)
		(layer "Edge.Cuts")
	)
	(gr_line
		(start 135.15 126.603553)
		(end 135.15 50.603553)
		(stroke
			(width 0.05)
			(type solid)
		)
		(locked yes)
		(layer "Edge.Cuts")
	)
	(gr_circle
		(center 140.66 70.6)
		(end 140.81 70.6)
		(stroke
			(width 0.1)
			(type solid)
		)
		(fill no)
		(layer "Edge.Cuts")
	)
	(gr_circle
		(center 142.9 70.6)
		(end 143.05 70.6)
		(stroke
			(width 0.1)
			(type solid)
		)
		(fill no)
		(layer "Edge.Cuts")
	)
	(gr_arc
		(start 156.08315 127.1)
		(mid 156.221673 126.755818)
		(end 156.56 126.603553)
		(stroke
			(width 0.05)
			(type default)
		)
		(layer "Edge.Cuts")
	)
	(gr_circle
		(center 142.16 70.6)
		(end 142.31 70.6)
		(stroke
			(width 0.1)
			(type solid)
		)
		(fill no)
		(layer "Edge.Cuts")
	)
	(gr_line
		(start 149.01 50.6)
		(end 148.2 50.6)
		(stroke
			(width 0.05)
			(type default)
		)
		(layer "Edge.Cuts")
	)
	(gr_line
		(start 156.08315 127.1)
		(end 156.08315 130.6)
		(stroke
			(width 0.05)
			(type default)
		)
		(layer "Edge.Cuts")
	)
	(gr_circle
		(center 152.4 70.6)
		(end 152.25 70.6)
		(stroke
			(width 0.1)
			(type solid)
		)
		(fill no)
		(layer "Edge.Cuts")
	)
	(gr_line
		(start 135.73 126.603553)
		(end 135.15 126.603553)
		(stroke
			(width 0.05)
			(type default)
		)
		(layer "Edge.Cuts")
	)
	(gr_arc
		(start 147.77 50.6)
		(mid 146.02 52.35)
		(end 144.27 50.6)
		(stroke
			(width 0.05)
			(type solid)
		)
		(layer "Edge.Cuts")
	)
	(gr_circle
		(center 156.6 70.6)
		(end 156.45 70.6)
		(stroke
			(width 0.1)
			(type solid)
		)
		(fill no)
		(layer "Edge.Cuts")
	)
	(gr_circle
		(center 136.41 70.6)
		(end 136.56 70.6)
		(stroke
			(width 0.1)
			(type solid)
		)
		(fill no)
		(layer "Edge.Cuts")
	)
	(gr_circle
		(center 137.81 70.6)
		(end 137.96 70.6)
		(stroke
			(width 0.1)
			(type solid)
		)
		(fill no)
		(layer "Edge.Cuts")
	)
	(gr_line
		(start 136.23 130.6)
		(end 136.23 127.2)
		(stroke
			(width 0.05)
			(type default)
		)
		(layer "Edge.Cuts")
	)
	(gr_circle
		(center 154.5 70.6)
		(end 154.35 70.6)
		(stroke
			(width 0.1)
			(type solid)
		)
		(fill no)
		(layer "Edge.Cuts")
	)
	(gr_line
		(start 156.56 126.603553)
		(end 157.15 126.603553)
		(stroke
			(width 0.05)
			(type default)
		)
		(layer "Edge.Cuts")
	)
	(gr_circle
		(center 150.9 70.6)
		(end 150.75 70.6)
		(stroke
			(width 0.1)
			(type solid)
		)
		(fill no)
		(layer "Edge.Cuts")
	)
	(gr_line
		(start 140.63 127.7)
		(end 140.63 127.75)
		(stroke
			(width 0.05)
			(type default)
		)
		(layer "Edge.Cuts")
	)
	(gr_circle
		(center 139.91 70.6)
		(end 140.06 70.6)
		(stroke
			(width 0.1)
			(type solid)
		)
		(fill no)
		(layer "Edge.Cuts")
	)
	(gr_text "${TITLE}"
		(at 148.65 77.25 0)
		(layer "F.Cu")
		(effects
			(font
				(size 0.7 0.7)
				(thickness 0.15)
				(bold yes)
			)
		)
	)
	(gr_text "Rev. 1.0.2 08/2025\n"
		(at 147.975 78.65 0)
		(layer "F.Cu")
		(effects
			(font
				(size 0.7 0.7)
				(thickness 0.15)
				(bold yes)
			)
		)
	)
	(segment
		(start 143.277041 97.142904)
		(end 143.277041 96.392904)
		(width 0.25)
		(layer "F.Cu")
		(net 1)
	)
	(segment
		(start 150.777041 97.077041)
		(end 150.777041 96.392904)
		(width 0.25)
		(layer "F.Cu")
		(net 1)
	)
	(segment
		(start 145.48 93.27)
		(end 145.48 92.76)
		(width 0.2)
		(layer "F.Cu")
		(net 1)
	)
	(segment
		(start 148.9 127.099998)
		(end 148.9 129.15)
		(width 0.35)
		(layer "F.Cu")
		(net 1)
	)
	(segment
		(start 147.267041 93.862882)
		(end 147.267041 94.282904)
		(width 0.25)
		(layer "F.Cu")
		(net 1)
	)
	(segment
		(start 144.76 97.03)
		(end 144.76 96.38)
		(width 0.25)
		(layer "F.Cu")
		(net 1)
	)
	(segment
		(start 153.327041 93.742904)
		(end 153.327041 94.272904)
		(width 0.4)
		(layer "F.Cu")
		(net 1)
	)
	(segment
		(start 146.33 97.442324)
		(end 146.211041 97.323365)
		(width 0.25)
		(layer "F.Cu")
		(net 1)
	)
	(segment
		(start 142.777041 93.739078)
		(end 142.777041 94.202904)
		(width 0.25)
		(layer "F.Cu")
		(net 1)
	)
	(segment
		(start 146.314591 97.598194)
		(end 146.33 97.582785)
		(width 0.25)
		(layer "F.Cu")
		(net 1)
	)
	(segment
		(start 151.896167 126.475)
		(end 151.896167 126.543666)
		(width 0.35)
		(layer "F.Cu")
		(net 1)
	)
	(segment
		(start 136.895243 126.652379)
		(end 136.895243 129.15)
		(width 0.25)
		(layer "F.Cu")
		(net 1)
	)
	(segment
		(start 144.27 93.648847)
		(end 144.27 93.713732)
		(width 0.25)
		(layer "F.Cu")
		(net 1)
	)
	(segment
		(start 155.375 125.835616)
		(end 154.9 126.310616)
		(width 0.35)
		(layer "F.Cu")
		(net 1)
	)
	(segment
		(start 154.9 126.310616)
		(end 154.9 129.15)
		(width 0.35)
		(layer "F.Cu")
		(net 1)
	)
	(segment
		(start 147.89 97.424644)
		(end 147.816435 97.498209)
		(width 0.25)
		(layer "F.Cu")
		(net 1)
	)
	(segment
		(start 142.8425 126.0425)
		(end 142.9 126.1)
		(width 0.35)
		(layer "F.Cu")
		(net 1)
	)
	(segment
		(start 136.32 120.58)
		(end 136.74 120.58)
		(width 0.4)
		(layer "F.Cu")
		(net 1)
	)
	(segment
		(start 147.901352 93.469591)
		(end 147.660332 93.469591)
		(width 0.25)
		(layer "F.Cu")
		(net 1)
	)
	(segment
		(start 146.211041 96.908323)
		(end 146.267041 96.852323)
		(width 0.25)
		(layer "F.Cu")
		(net 1)
	)
	(segment
		(start 153.327041 98.192904)
		(end 153.327041 98.992904)
		(width 0.4)
		(layer "F.Cu")
		(net 1)
	)
	(segment
		(start 151.896167 126.543666)
		(end 151.9 126.547499)
		(width 0.35)
		(layer "F.Cu")
		(net 1)
	)
	(segment
		(start 148.777041 93.653879)
		(end 148.777041 94.202904)
		(width 0.25)
		(layer "F.Cu")
		(net 1)
	)
	(segment
		(start 145.9 127.066898)
		(end 145.9 129.15)
		(width 0.35)
		(layer "F.Cu")
		(net 1)
	)
	(segment
		(start 151.9 126.547499)
		(end 151.9 129.15)
		(width 0.35)
		(layer "F.Cu")
		(net 1)
	)
	(segment
		(start 142.638981 93.601019)
		(end 142.777041 93.739078)
		(width 0.25)
		(layer "F.Cu")
		(net 1)
	)
	(segment
		(start 148.879965 127.004483)
		(end 148.93 127.054518)
		(width 0.35)
		(layer "F.Cu")
		(net 1)
	)
	(segment
		(start 147.277041 93.842993)
		(end 147.277041 94.202904)
		(width 0.25)
		(layer "F.Cu")
		(net 1)
	)
	(segment
		(start 147.767041 96.797041)
		(end 147.89 96.92)
		(width 0.25)
		(layer "F.Cu")
		(net 1)
	)
	(segment
		(start 153.35 127.038482)
		(end 153.4 127.088482)
		(width 0.35)
		(layer "F.Cu")
		(net 1)
	)
	(segment
		(start 144.278134 93.721866)
		(end 144.278134 93.821866)
		(width 0.25)
		(layer "F.Cu")
		(net 1)
	)
	(segment
		(start 141.777041 96.992904)
		(end 141.777041 96.392904)
		(width 0.25)
		(layer "F.Cu")
		(net 1)
	)
	(segment
		(start 153.35 127.015014)
		(end 153.35 127.038482)
		(width 0.35)
		(layer "F.Cu")
		(net 1)
	)
	(segment
		(start 147.4 127.035237)
		(end 147.405237 127.03)
		(width 0.35)
		(layer "F.Cu")
		(net 1)
	)
	(segment
		(start 144.271 93.647847)
		(end 144.27 93.648847)
		(width 0.25)
		(layer "F.Cu")
		(net 1)
	)
	(segment
		(start 150.4 127.056169)
		(end 150.4 129.15)
		(width 0.35)
		(layer "F.Cu")
		(net 1)
	)
	(segment
		(start 145.641341 93.431341)
		(end 145.48 93.27)
		(width 0.2)
		(layer "F.Cu")
		(net 1)
	)
	(segment
		(start 136.71 123.71)
		(end 136.14 123.71)
		(width 0.4)
		(layer "F.Cu")
		(net 1)
	)
	(segment
		(start 144.412023 127.03)
		(end 144.412023 127.046426)
		(width 0.35)
		(layer "F.Cu")
		(net 1)
	)
	(segment
		(start 141.4 127.243285)
		(end 141.138396 126.981681)
		(width 0.35)
		(layer "F.Cu")
		(net 1)
	)
	(segment
		(start 137.35 126.6)
		(end 137.4 126.65)
		(width 0.25)
		(layer "F.Cu")
		(net 1)
	)
	(segment
		(start 147.89 96.92)
		(end 147.89 97.424644)
		(width 0.25)
		(layer "F.Cu")
		(net 1)
	)
	(segment
		(start 144.27 93.713732)
		(end 144.278134 93.721866)
		(width 0.25)
		(layer "F.Cu")
		(net 1)
	)
	(segment
		(start 145.767041 94.282904)
		(end 145.767041 93.909759)
		(width 0.2)
		(layer "F.Cu")
		(net 1)
	)
	(segment
		(start 153.334595 126.999609)
		(end 153.35 127.015014)
		(width 0.35)
		(layer "F.Cu")
		(net 1)
	)
	(segment
		(start 145.641341 93.784059)
		(end 145.641341 93.431341)
		(width 0.2)
		(layer "F.Cu")
		(net 1)
	)
	(segment
		(start 137.35 126.53905)
		(end 137.35 126.6)
		(width 0.25)
		(layer "F.Cu")
		(net 1)
	)
	(segment
		(start 155.4 126.55)
		(end 155.4 129.15)
		(width 0.35)
		(layer "F.Cu")
		(net 1)
	)
	(segment
		(start 150.390512 127.046681)
		(end 150.4 127.056169)
		(width 0.35)
		(layer "F.Cu")
		(net 1)
	)
	(segment
		(start 144.4 127.058449)
		(end 144.4 129.141551)
		(width 0.35)
		(layer "F.Cu")
		(net 1)
	)
	(segment
		(start 156.125 125.825)
		(end 155.4 126.55)
		(width 0.35)
		(layer "F.Cu")
		(net 1)
	)
	(segment
		(start 144.412023 127.046426)
		(end 144.4 127.058449)
		(width 0.35)
		(layer "F.Cu")
		(net 1)
	)
	(segment
		(start 148.93 127.054518)
		(end 148.93 127.069998)
		(width 0.35)
		(layer "F.Cu")
		(net 1)
	)
	(segment
		(start 155.375 125.79)
		(end 155.375 125.835616)
		(width 0.35)
		(layer "F.Cu")
		(net 1)
	)
	(segment
		(start 148.768843 93.645681)
		(end 148.777041 93.653879)
		(width 0.25)
		(layer "F.Cu")
		(net 1)
	)
	(segment
		(start 140.277041 99.492904)
		(end 139.207041 99.492904)
		(width 0.4)
		(layer "F.Cu")
		(net 1)
	)
	(segment
		(start 147.4 129.15)
		(end 147.4 127.035237)
		(width 0.35)
		(layer "F.Cu")
		(net 1)
	)
	(segment
		(start 141.677041 97.192904)
		(end 141.677041 97.092904)
		(width 0.25)
		(layer "F.Cu")
		(net 1)
	)
	(segment
		(start 137.4 126.65)
		(end 137.4 129.147621)
		(width 0.25)
		(layer "F.Cu")
		(net 1)
	)
	(segment
		(start 137.36305 126.526)
		(end 137.35 126.53905)
		(width 0.25)
		(layer "F.Cu")
		(net 1)
	)
	(segment
		(start 145.91 127.056898)
		(end 145.9 127.066898)
		(width 0.35)
		(layer "F.Cu")
		(net 1)
	)
	(segment
		(start 150.293649 93.526296)
		(end 150.277041 93.542904)
		(width 0.25)
		(layer "F.Cu")
		(net 1)
	)
	(segment
		(start 137.9 126.65)
		(end 137.9 129.147621)
		(width 0.25)
		(layer "F.Cu")
		(net 1)
	)
	(segment
		(start 146.33 97.582785)
		(end 146.33 97.442324)
		(width 0.25)
		(layer "F.Cu")
		(net 1)
	)
	(segment
		(start 144.278134 93.821866)
		(end 144.277041 93.822959)
		(width 0.25)
		(layer "F.Cu")
		(net 1)
	)
	(segment
		(start 145.13 97.4)
		(end 144.76 97.03)
		(width 0.25)
		(layer "F.Cu")
		(net 1)
	)
	(segment
		(start 145.48 92.76)
		(end 145.49 92.75)
		(width 0.2)
		(layer "F.Cu")
		(net 1)
	)
	(segment
		(start 148.93 127.069998)
		(end 148.9 127.099998)
		(width 0.35)
		(layer "F.Cu")
		(net 1)
	)
	(segment
		(start 141.277041 94.202904)
		(end 141.277041 93.392904)
		(width 0.25)
		(layer "F.Cu")
		(net 1)
	)
	(segment
		(start 140.4 95.05)
		(end 139.75 95.05)
		(width 0.4)
		(layer "F.Cu")
		(net 1)
	)
	(segment
		(start 147.767041 96.472904)
		(end 147.767041 96.797041)
		(width 0.25)
		(layer "F.Cu")
		(net 1)
	)
	(segment
		(start 147.660332 93.469591)
		(end 147.267041 93.862882)
		(width 0.25)
		(layer "F.Cu")
		(net 1)
	)
	(segment
		(start 146.267041 96.852323)
		(end 146.267041 96.472904)
		(width 0.25)
		(layer "F.Cu")
		(net 1)
	)
	(segment
		(start 145.767041 93.909759)
		(end 145.641341 93.784059)
		(width 0.2)
		(layer "F.Cu")
		(net 1)
	)
	(segment
		(start 150.86 97.16)
		(end 150.777041 97.077041)
		(width 0.25)
		(layer "F.Cu")
		(net 1)
	)
	(segment
		(start 153.4 127.088482)
		(end 153.4 129.15)
		(width 0.35)
		(layer "F.Cu")
		(net 1)
	)
	(segment
		(start 150.277041 93.542904)
		(end 150.277041 94.202904)
		(width 0.25)
		(layer "F.Cu")
		(net 1)
	)
	(segment
		(start 149.27 95.23)
		(end 149.27 96.5)
		(width 0.2)
		(layer "F.Cu")
		(net 1)
	)
	(segment
		(start 141.4 129.15)
		(end 141.4 127.243285)
		(width 0.35)
		(layer "F.Cu")
		(net 1)
	)
	(segment
		(start 148.768541 93.645681)
		(end 148.768843 93.645681)
		(width 0.25)
		(layer "F.Cu")
		(net 1)
	)
	(segment
		(start 141.677041 97.092904)
		(end 141.777041 96.992904)
		(width 0.25)
		(layer "F.Cu")
		(net 1)
	)
	(segment
		(start 136.04 120.86)
		(end 136.32 120.58)
		(width 0.4)
		(layer "F.Cu")
		(net 1)
	)
	(segment
		(start 136.75 126.507136)
		(end 136.895243 126.652379)
		(width 0.25)
		(layer "F.Cu")
		(net 1)
	)
	(segment
		(start 142.9 126.1)
		(end 142.9 129.15)
		(width 0.35)
		(layer "F.Cu")
		(net 1)
	)
	(segment
		(start 150.375643 93.526296)
		(end 150.293649 93.526296)
		(width 0.25)
		(layer "F.Cu")
		(net 1)
	)
	(segment
		(start 145.91 127.03)
		(end 145.91 127.056898)
		(width 0.35)
		(layer "F.Cu")
		(net 1)
	)
	(segment
		(start 146.211041 97.323365)
		(end 146.211041 96.908323)
		(width 0.25)
		(layer "F.Cu")
		(net 1)
	)
	(segment
		(start 144.277041 93.822959)
		(end 144.277041 94.202904)
		(width 0.25)
		(layer "F.Cu")
		(net 1)
	)
	(via
		(at 156.3 54.65)
		(size 0.5)
		(drill 0.2)
		(layers "F.Cu" "B.Cu")
		(remove_unused_layers yes)
		(keep_end_layers yes)
		(free yes)
		(zone_layer_connections "In1.Cu" "In2.Cu")
		(teardrops
			(best_length_ratio 0.5)
			(max_length 1)
			(best_width_ratio 1)
			(max_width 2)
			(curved_edges yes)
			(filter_ratio 0.9)
			(enabled no)
			(allow_two_segments yes)
			(prefer_zone_connections yes)
		)
		(net 1)
	)
	(via
		(at 143.277041 97.142904)
		(size 0.5)
		(drill 0.2)
		(layers "F.Cu" "B.Cu")
		(remove_unused_layers yes)
		(keep_end_layers yes)
		(zone_layer_connections "In1.Cu" "In2.Cu")
		(teardrops
			(best_length_ratio 0.5)
			(max_length 1)
			(best_width_ratio 1)
			(max_width 2)
			(curved_edges yes)
			(filter_ratio 0.9)
			(enabled no)
			(allow_two_segments yes)
			(prefer_zone_connections no)
		)
		(net 1)
	)
	(via
		(at 156.3 115.329343)
		(size 0.5)
		(drill 0.2)
		(layers "F.Cu" "B.Cu")
		(remove_unused_layers yes)
		(keep_end_layers yes)
		(free yes)
		(zone_layer_connections "In1.Cu" "In2.Cu")
		(teardrops
			(best_length_ratio 0.5)
			(max_length 1)
			(best_width_ratio 1)
			(max_width 2)
			(curved_edges yes)
			(filter_ratio 0.9)
			(enabled no)
			(allow_two_segments yes)
			(prefer_zone_connections yes)
		)
		(net 1)
	)
	(via
		(at 153.327041 98.192904)
		(size 0.5)
		(drill 0.2)
		(layers "F.Cu" "B.Cu")
		(remove_unused_layers yes)
		(keep_end_layers yes)
		(zone_layer_connections "In1.Cu" "In2.Cu")
		(teardrops
			(best_length_ratio 0.5)
			(max_length 1)
			(best_width_ratio 1)
			(max_width 2)
			(curved_edges yes)
			(filter_ratio 0.9)
			(enabled no)
			(allow_two_segments yes)
			(prefer_zone_connections no)
		)
		(net 1)
	)
	(via
		(at 153.39054 125.72595)
		(size 0.5)
		(drill 0.2)
		(layers "F.Cu" "B.Cu")
		(remove_unused_layers yes)
		(keep_end_layers yes)
		(zone_layer_connections "In1.Cu" "In2.Cu")
		(teardrops
			(best_length_ratio 0.5)
			(max_length 1)
			(best_width_ratio 1)
			(max_width 2)
			(curved_edges yes)
			(filter_ratio 0.9)
			(enabled no)
			(allow_two_segments yes)
			(prefer_zone_connections no)
		)
		(net 1)
	)
	(via
		(at 153.8 71.5)
		(size 0.5)
		(drill 0.2)
		(layers "F.Cu" "B.Cu")
		(remove_unused_layers yes)
		(keep_end_layers yes)
		(free yes)
		(zone_layer_connections "In1.Cu" "In2.Cu")
		(teardrops
			(best_length_ratio 0.5)
			(max_length 1)
			(best_width_ratio 1)
			(max_width 2)
			(curved_edges yes)
			(filter_ratio 0.9)
			(enabled no)
			(allow_two_segments yes)
			(prefer_zone_connections yes)
		)
		(net 1)
	)
	(via
		(at 148.768541 93.645681)
		(size 0.5)
		(drill 0.2)
		(layers "F.Cu" "B.Cu")
		(remove_unused_layers yes)
		(keep_end_layers yes)
		(zone_layer_connections "In1.Cu" "In2.Cu")
		(teardrops
			(best_length_ratio 0.5)
			(max_length 1)
			(best_width_ratio 1)
			(max_width 2)
			(curved_edges yes)
			(filter_ratio 0.9)
			(enabled no)
			(allow_two_segments yes)
			(prefer_zone_connections no)
		)
		(net 1)
	)
	(via
		(at 156.3 72.829343)
		(size 0.5)
		(drill 0.2)
		(layers "F.Cu" "B.Cu")
		(remove_unused_layers yes)
		(keep_end_layers yes)
		(free yes)
		(zone_layer_connections "In1.Cu" "In2.Cu")
		(teardrops
			(best_length_ratio 0.5)
			(max_length 1)
			(best_width_ratio 1)
			(max_width 2)
			(curved_edges yes)
			(filter_ratio 0.9)
			(enabled no)
			(allow_two_segments yes)
			(prefer_zone_connections yes)
		)
		(net 1)
	)
	(via
		(at 156.3 85.329343)
		(size 0.5)
		(drill 0.2)
		(layers "F.Cu" "B.Cu")
		(remove_unused_layers yes)
		(keep_end_layers yes)
		(free yes)
		(zone_layer_connections "In1.Cu" "In2.Cu")
		(teardrops
			(best_length_ratio 0.5)
			(max_length 1)
			(best_width_ratio 1)
			(max_width 2)
			(curved_edges yes)
			(filter_ratio 0.9)
			(enabled no)
			(allow_two_segments yes)
			(prefer_zone_connections yes)
		)
		(net 1)
	)
	(via
		(at 149.27 95.23)
		(size 0.5)
		(drill 0.2)
		(layers "F.Cu" "B.Cu")
		(remove_unused_layers yes)
		(keep_end_layers yes)
		(zone_layer_connections "In1.Cu" "In2.Cu")
		(teardrops
			(best_length_ratio 0.5)
			(max_length 1)
			(best_width_ratio 1)
			(max_width 2)
			(curved_edges yes)
			(filter_ratio 0.9)
			(enabled no)
			(allow_two_segments yes)
			(prefer_zone_connections no)
		)
		(net 1)
	)
	(via
		(at 156.3 80.33)
		(size 0.5)
		(drill 0.2)
		(layers "F.Cu" "B.Cu")
		(remove_unused_layers yes)
		(keep_end_layers yes)
		(free yes)
		(zone_layer_connections "In1.Cu" "In2.Cu")
		(teardrops
			(best_length_ratio 0.5)
			(max_length 1)
			(best_width_ratio 1)
			(max_width 2)
			(curved_edges yes)
			(filter_ratio 0.9)
			(enabled no)
			(allow_two_segments yes)
			(prefer_zone_connections yes)
		)
		(net 1)
	)
	(via
		(at 137.36305 126.526)
		(size 0.5)
		(drill 0.2)
		(layers "F.Cu" "B.Cu")
		(remove_unused_layers yes)
		(keep_end_layers yes)
		(free yes)
		(zone_layer_connections "In1.Cu" "In2.Cu")
		(teardrops
			(best_length_ratio 0.5)
			(max_length 1)
			(best_width_ratio 1)
			(max_width 2)
			(curved_edges yes)
			(filter_ratio 0.9)
			(enabled no)
			(allow_two_segments yes)
			(prefer_zone_connections yes)
		)
		(net 1)
	)
	(via
		(at 156.3 69.65)
		(size 0.5)
		(drill 0.2)
		(layers "F.Cu" "B.Cu")
		(remove_unused_layers yes)
		(keep_end_layers yes)
		(free yes)
		(zone_layer_connections "In1.Cu" "In2.Cu")
		(teardrops
			(best_length_ratio 0.5)
			(max_length 1)
			(best_width_ratio 1)
			(max_width 2)
			(curved_edges yes)
			(filter_ratio 0.9)
			(enabled no)
			(allow_two_segments yes)
			(prefer_zone_connections yes)
		)
		(net 1)
	)
	(via
		(at 156.3 95.329343)
		(size 0.5)
		(drill 0.2)
		(layers "F.Cu" "B.Cu")
		(remove_unused_layers yes)
		(keep_end_layers yes)
		(free yes)
		(zone_layer_connections "In1.Cu" "In2.Cu")
		(teardrops
			(best_length_ratio 0.5)
			(max_length 1)
			(best_width_ratio 1)
			(max_width 2)
			(curved_edges yes)
			(filter_ratio 0.9)
			(enabled no)
			(allow_two_segments yes)
			(prefer_zone_connections yes)
		)
		(net 1)
	)
	(via
		(at 147.393752 124.543634)
		(size 0.5)
		(drill 0.2)
		(layers "F.Cu" "B.Cu")
		(remove_unused_layers yes)
		(keep_end_layers yes)
		(zone_layer_connections "In1.Cu" "In2.Cu")
		(teardrops
			(best_length_ratio 0.5)
			(max_length 1)
			(best_width_ratio 1)
			(max_width 2)
			(curved_edges yes)
			(filter_ratio 0.9)
			(enabled no)
			(allow_two_segments yes)
			(prefer_zone_connections no)
		)
		(net 1)
	)
	(via
		(at 155.375 125.79)
		(size 0.5)
		(drill 0.2)
		(layers "F.Cu" "B.Cu")
		(remove_unused_layers yes)
		(keep_end_layers yes)
		(zone_layer_connections "In1.Cu" "In2.Cu")
		(teardrops
			(best_length_ratio 0.5)
			(max_length 1)
			(best_width_ratio 1)
			(max_width 2)
			(curved_edges yes)
			(filter_ratio 0.9)
			(enabled no)
			(allow_two_segments yes)
			(prefer_zone_connections no)
		)
		(net 1)
	)
	(via
		(at 135.95 71.5)
		(size 0.5)
		(drill 0.2)
		(layers "F.Cu" "B.Cu")
		(remove_unused_layers yes)
		(keep_end_layers yes)
		(free yes)
		(zone_layer_connections "In1.Cu" "In2.Cu")
		(teardrops
			(best_length_ratio 0.5)
			(max_length 1)
			(best_width_ratio 1)
			(max_width 2)
			(curved_edges yes)
			(filter_ratio 0.9)
			(enabled no)
			(allow_two_segments yes)
			(prefer_zone_connections yes)
		)
		(net 1)
	)
	(via
		(at 135.95 92.6)
		(size 0.5)
		(drill 0.2)
		(layers "F.Cu" "B.Cu")
		(remove_unused_layers yes)
		(keep_end_layers yes)
		(free yes)
		(zone_layer_connections "In1.Cu" "In2.Cu")
		(teardrops
			(best_length_ratio 0.5)
			(max_length 1)
			(best_width_ratio 1)
			(max_width 2)
			(curved_edges yes)
			(filter_ratio 0.9)
			(enabled no)
			(allow_two_segments yes)
			(prefer_zone_connections yes)
		)
		(net 1)
	)
	(via
		(at 136.75 126.507136)
		(size 0.5)
		(drill 0.2)
		(layers "F.Cu" "B.Cu")
		(remove_unused_layers yes)
		(keep_end_layers yes)
		(zone_layer_connections "In1.Cu" "In2.Cu")
		(teardrops
			(best_length_ratio 0.5)
			(max_length 1)
			(best_width_ratio 1)
			(max_width 2)
			(curved_edges yes)
			(filter_ratio 0.9)
			(enabled no)
			(allow_two_segments yes)
			(prefer_zone_connections yes)
		)
		(net 1)
	)
	(via
		(at 145.49 92.75)
		(size 0.5)
		(drill 0.2)
		(layers "F.Cu" "B.Cu")
		(remove_unused_layers yes)
		(keep_end_layers yes)
		(free yes)
		(zone_layer_connections "In1.Cu" "In2.Cu")
		(net 1)
	)
	(via
		(at 156.3 64.65)
		(size 0.5)
		(drill 0.2)
		(layers "F.Cu" "B.Cu")
		(remove_unused_layers yes)
		(keep_end_layers yes)
		(free yes)
		(zone_layer_connections "In1.Cu" "In2.Cu")
		(teardrops
			(best_length_ratio 0.5)
			(max_length 1)
			(best_width_ratio 1)
			(max_width 2)
			(curved_edges yes)
			(filter_ratio 0.9)
			(enabled no)
			(allow_two_segments yes)
			(prefer_zone_connections yes)
		)
		(net 1)
	)
	(via
		(at 140.04 97.9)
		(size 0.5)
		(drill 0.2)
		(layers "F.Cu" "B.Cu")
		(remove_unused_layers yes)
		(keep_end_layers yes)
		(zone_layer_connections "In1.Cu" "In2.Cu")
		(net 1)
	)
	(via
		(at 135.95 117.6)
		(size 0.5)
		(drill 0.2)
		(layers "F.Cu" "B.Cu")
		(remove_unused_layers yes)
		(keep_end_layers yes)
		(free yes)
		(zone_layer_connections "In1.Cu" "In2.Cu")
		(teardrops
			(best_length_ratio 0.5)
			(max_length 1)
			(best_width_ratio 1)
			(max_width 2)
			(curved_edges yes)
			(filter_ratio 0.9)
			(enabled no)
			(allow_two_segments yes)
			(prefer_zone_connections yes)
		)
		(net 1)
	)
	(via
		(at 145 52.8)
		(size 0.5)
		(drill 0.2)
		(layers "F.Cu" "B.Cu")
		(remove_unused_layers yes)
		(keep_end_layers yes)
		(free yes)
		(zone_layer_connections "In1.Cu" "In2.Cu")
		(teardrops
			(best_length_ratio 0.5)
			(max_length 1)
			(best_width_ratio 1)
			(max_width 2)
			(curved_edges yes)
			(filter_ratio 0.9)
			(enabled no)
			(allow_two_segments yes)
			(prefer_zone_connections yes)
		)
		(net 1)
	)
	(via
		(at 138.45 51.4)
		(size 0.5)
		(drill 0.2)
		(layers "F.Cu" "B.Cu")
		(remove_unused_layers yes)
		(keep_end_layers yes)
		(free yes)
		(zone_layer_connections "In1.Cu" "In2.Cu")
		(teardrops
			(best_length_ratio 0.5)
			(max_length 1)
			(best_width_ratio 1)
			(max_width 2)
			(curved_edges yes)
			(filter_ratio 0.9)
			(enabled no)
			(allow_two_segments yes)
			(prefer_zone_connections yes)
		)
		(net 1)
	)
	(via
		(at 135.95 115.1)
		(size 0.5)
		(drill 0.2)
		(layers "F.Cu" "B.Cu")
		(remove_unused_layers yes)
		(keep_end_layers yes)
		(free yes)
		(zone_layer_connections "In1.Cu" "In2.Cu")
		(teardrops
			(best_length_ratio 0.5)
			(max_length 1)
			(best_width_ratio 1)
			(max_width 2)
			(curved_edges yes)
			(filter_ratio 0.9)
			(enabled no)
			(allow_two_segments yes)
			(prefer_zone_connections yes)
		)
		(net 1)
	)
	(via
		(at 135.95 67.1)
		(size 0.5)
		(drill 0.2)
		(layers "F.Cu" "B.Cu")
		(remove_unused_layers yes)
		(keep_end_layers yes)
		(free yes)
		(zone_layer_connections "In1.Cu" "In2.Cu")
		(teardrops
			(best_length_ratio 0.5)
			(max_length 1)
			(best_width_ratio 1)
			(max_width 2)
			(curved_edges yes)
			(filter_ratio 0.9)
			(enabled no)
			(allow_two_segments yes)
			(prefer_zone_connections yes)
		)
		(net 1)
	)
	(via
		(at 137.908768 126.501232)
		(size 0.5)
		(drill 0.2)
		(layers "F.Cu" "B.Cu")
		(remove_unused_layers yes)
		(keep_end_layers yes)
		(zone_layer_connections "In1.Cu" "In2.Cu")
		(teardrops
			(best_length_ratio 0.5)
			(max_length 1)
			(best_width_ratio 1)
			(max_width 2)
			(curved_edges yes)
			(filter_ratio 0.9)
			(enabled no)
			(allow_two_segments yes)
			(prefer_zone_connections yes)
		)
		(net 1)
	)
	(via
		(at 140.95 51.4)
		(size 0.5)
		(drill 0.2)
		(layers "F.Cu" "B.Cu")
		(remove_unused_layers yes)
		(keep_end_layers yes)
		(free yes)
		(zone_layer_connections "In1.Cu" "In2.Cu")
		(teardrops
			(best_length_ratio 0.5)
			(max_length 1)
			(best_width_ratio 1)
			(max_width 2)
			(curved_edges yes)
			(filter_ratio 0.9)
			(enabled no)
			(allow_two_segments yes)
			(prefer_zone_connections yes)
		)
		(net 1)
	)
	(via
		(at 142.87 95.58)
		(size 0.5)
		(drill 0.2)
		(layers "F.Cu" "B.Cu")
		(remove_unused_layers yes)
		(keep_end_layers yes)
		(zone_layer_connections "In1.Cu" "In2.Cu")
		(teardrops
			(best_length_ratio 0.5)
			(max_length 1)
			(best_width_ratio 1)
			(max_width 2)
			(curved_edges yes)
			(filter_ratio 0.9)
			(enabled no)
			(allow_two_segments yes)
			(prefer_zone_connections no)
		)
		(net 1)
	)
	(via
		(at 150.375643 93.526296)
		(size 0.5)
		(drill 0.2)
		(layers "F.Cu" "B.Cu")
		(remove_unused_layers yes)
		(keep_end_layers yes)
		(zone_layer_connections "In1.Cu" "In2.Cu")
		(teardrops
			(best_length_ratio 0.5)
			(max_length 1)
			(best_width_ratio 1)
			(max_width 2)
			(curved_edges yes)
			(filter_ratio 0.9)
			(enabled no)
			(allow_two_segments yes)
			(prefer_zone_connections no)
		)
		(net 1)
	)
	(via
		(at 145.902221 124.552979)
		(size 0.5)
		(drill 0.2)
		(layers "F.Cu" "B.Cu")
		(remove_unused_layers yes)
		(keep_end_layers yes)
		(zone_layer_connections "In1.Cu" "In2.Cu")
		(teardrops
			(best_length_ratio 0.5)
			(max_length 1)
			(best_width_ratio 1)
			(max_width 2)
			(curved_edges yes)
			(filter_ratio 0.9)
			(enabled no)
			(allow_two_segments yes)
			(prefer_zone_connections no)
		)
		(net 1)
	)
	(via
		(at 156.3 112.829343)
		(size 0.5)
		(drill 0.2)
		(layers "F.Cu" "B.Cu")
		(remove_unused_layers yes)
		(keep_end_layers yes)
		(free yes)
		(zone_layer_connections "In1.Cu" "In2.Cu")
		(teardrops
			(best_length_ratio 0.5)
			(max_length 1)
			(best_width_ratio 1)
			(max_width 2)
			(curved_edges yes)
			(filter_ratio 0.9)
			(enabled no)
			(allow_two_segments yes)
			(prefer_zone_connections yes)
		)
		(net 1)
	)
	(via
		(at 156.3 90.329343)
		(size 0.5)
		(drill 0.2)
		(layers "F.Cu" "B.Cu")
		(remove_unused_layers yes)
		(keep_end_layers yes)
		(free yes)
		(zone_layer_connections "In1.Cu" "In2.Cu")
		(teardrops
			(best_length_ratio 0.5)
			(max_length 1)
			(best_width_ratio 1)
			(max_width 2)
			(curved_edges yes)
			(filter_ratio 0.9)
			(enabled no)
			(allow_two_segments yes)
			(prefer_zone_connections yes)
		)
		(net 1)
	)
	(via
		(at 156.3 52.15)
		(size 0.5)
		(drill 0.2)
		(layers "F.Cu" "B.Cu")
		(remove_unused_layers yes)
		(keep_end_layers yes)
		(free yes)
		(zone_layer_connections "In1.Cu" "In2.Cu")
		(teardrops
			(best_length_ratio 0.5)
			(max_length 1)
			(best_width_ratio 1)
			(max_width 2)
			(curved_edges yes)
			(filter_ratio 0.9)
			(enabled no)
			(allow_two_segments yes)
			(prefer_zone_connections yes)
		)
		(net 1)
	)
	(via
		(at 150.404083 92.596354)
		(size 0.5)
		(drill 0.2)
		(layers "F.Cu" "B.Cu")
		(remove_unused_layers yes)
		(keep_end_layers yes)
		(zone_layer_connections "In1.Cu" "In2.Cu")
		(teardrops
			(best_length_ratio 0.5)
			(max_length 1)
			(best_width_ratio 1)
			(max_width 2)
			(curved_edges yes)
			(filter_ratio 0.9)
			(enabled no)
			(allow_two_segments yes)
			(prefer_zone_connections no)
		)
		(net 1)
	)
	(via
		(at 135.95 54.6)
		(size 0.5)
		(drill 0.2)
		(layers "F.Cu" "B.Cu")
		(remove_unused_layers yes)
		(keep_end_layers yes)
		(free yes)
		(zone_layer_connections "In1.Cu" "In2.Cu")
		(teardrops
			(best_length_ratio 0.5)
			(max_length 1)
			(best_width_ratio 1)
			(max_width 2)
			(curved_edges yes)
			(filter_ratio 0.9)
			(enabled no)
			(allow_two_segments yes)
			(prefer_zone_connections yes)
		)
		(net 1)
	)
	(via
		(at 135.95 122.6)
		(size 0.5)
		(drill 0.2)
		(layers "F.Cu" "B.Cu")
		(remove_unused_layers yes)
		(keep_end_layers yes)
		(free yes)
		(zone_layer_connections "In1.Cu" "In2.Cu")
		(teardrops
			(best_length_ratio 0.5)
			(max_length 1)
			(best_width_ratio 1)
			(max_width 2)
			(curved_edges yes)
			(filter_ratio 0.9)
			(enabled no)
			(allow_two_segments yes)
			(prefer_zone_connections yes)
		)
		(net 1)
	)
	(via
		(at 135.95 102.6)
		(size 0.5)
		(drill 0.2)
		(layers "F.Cu" "B.Cu")
		(remove_unused_layers yes)
		(keep_end_layers yes)
		(free yes)
		(zone_layer_connections "In1.Cu" "In2.Cu")
		(teardrops
			(best_length_ratio 0.5)
			(max_length 1)
			(best_width_ratio 1)
			(max_width 2)
			(curved_edges yes)
			(filter_ratio 0.9)
			(enabled no)
			(allow_two_segments yes)
			(prefer_zone_connections yes)
		)
		(net 1)
	)
	(via
		(at 146.15 88.6)
		(size 5.5)
		(drill 3.5)
		(layers "F.Cu" "B.Cu")
		(remove_unused_layers yes)
		(keep_end_layers yes)
		(locked yes)
		(free yes)
		(zone_layer_connections "In1.Cu" "In2.Cu")
		(tenting none)
		(teardrops
			(best_length_ratio 0.5)
			(max_length 1)
			(best_width_ratio 1)
			(max_width 2)
			(curved_edges yes)
			(filter_ratio 0.9)
			(enabled no)
			(allow_two_segments yes)
			(prefer_zone_connections no)
		)
		(net 1)
	)
	(via
		(at 150.481912 122.965066)
		(size 0.5)
		(drill 0.2)
		(layers "F.Cu" "B.Cu")
		(remove_unused_layers yes)
		(keep_end_layers yes)
		(zone_layer_connections "In1.Cu" "In2.Cu")
		(teardrops
			(best_length_ratio 0.5)
			(max_length 1)
			(best_width_ratio 1)
			(max_width 2)
			(curved_edges yes)
			(filter_ratio 0.9)
			(enabled no)
			(allow_two_segments yes)
			(prefer_zone_connections no)
		)
		(net 1)
	)
	(via
		(at 156.3 62.15)
		(size 0.5)
		(drill 0.2)
		(layers "F.Cu" "B.Cu")
		(remove_unused_layers yes)
		(keep_end_layers yes)
		(free yes)
		(zone_layer_connections "In1.Cu" "In2.Cu")
		(teardrops
			(best_length_ratio 0.5)
			(max_length 1)
			(best_width_ratio 1)
			(max_width 2)
			(curved_edges yes)
			(filter_ratio 0.9)
			(enabled no)
			(allow_two_segments yes)
			(prefer_zone_connections yes)
		)
		(net 1)
	)
	(via
		(at 138.220606 115.870429)
		(size 0.5)
		(drill 0.2)
		(layers "F.Cu" "B.Cu")
		(remove_unused_layers yes)
		(keep_end_layers yes)
		(zone_layer_connections "In1.Cu" "In2.Cu")
		(teardrops
			(best_length_ratio 0.5)
			(max_length 1)
			(best_width_ratio 1)
			(max_width 2)
			(curved_edges yes)
			(filter_ratio 0.9)
			(enabled no)
			(allow_two_segments yes)
			(prefer_zone_connections no)
		)
		(net 1)
	)
	(via
		(at 135.95 72.6)
		(size 0.5)
		(drill 0.2)
		(layers "F.Cu" "B.Cu")
		(remove_unused_layers yes)
		(keep_end_layers yes)
		(free yes)
		(zone_layer_connections "In1.Cu" "In2.Cu")
		(teardrops
			(best_length_ratio 0.5)
			(max_length 1)
			(best_width_ratio 1)
			(max_width 2)
			(curved_edges yes)
			(filter_ratio 0.9)
			(enabled no)
			(allow_two_segments yes)
			(prefer_zone_connections yes)
		)
		(net 1)
	)
	(via
		(at 144.475523 123.105593)
		(size 0.5)
		(drill 0.2)
		(layers "F.Cu" "B.Cu")
		(remove_unused_layers yes)
		(keep_end_layers yes)
		(zone_layer_connections "In1.Cu" "In2.Cu")
		(teardrops
			(best_length_ratio 0.5)
			(max_length 1)
			(best_width_ratio 1)
			(max_width 2)
			(curved_edges yes)
			(filter_ratio 0.9)
			(enabled no)
			(allow_two_segments yes)
			(prefer_zone_connections no)
		)
		(net 1)
	)
	(via
		(at 135.95 107.6)
		(size 0.5)
		(drill 0.2)
		(layers "F.Cu" "B.Cu")
		(remove_unused_layers yes)
		(keep_end_layers yes)
		(free yes)
		(zone_layer_connections "In1.Cu" "In2.Cu")
		(teardrops
			(best_length_ratio 0.5)
			(max_length 1)
			(best_width_ratio 1)
			(max_width 2)
			(curved_edges yes)
			(filter_ratio 0.9)
			(enabled no)
			(allow_two_segments yes)
			(prefer_zone_connections yes)
		)
		(net 1)
	)
	(via
		(at 135.95 125.1)
		(size 0.5)
		(drill 0.2)
		(layers "F.Cu" "B.Cu")
		(remove_unused_layers yes)
		(keep_end_layers yes)
		(free yes)
		(zone_layer_connections "In1.Cu" "In2.Cu")
		(teardrops
			(best_length_ratio 0.5)
			(max_length 1)
			(best_width_ratio 1)
			(max_width 2)
			(curved_edges yes)
			(filter_ratio 0.9)
			(enabled no)
			(allow_two_segments yes)
			(prefer_zone_connections yes)
		)
		(net 1)
	)
	(via
		(at 156.3 75.329343)
		(size 0.5)
		(drill 0.2)
		(layers "F.Cu" "B.Cu")
		(remove_unused_layers yes)
		(keep_end_layers yes)
		(free yes)
		(zone_layer_connections "In1.Cu" "In2.Cu")
		(teardrops
			(best_length_ratio 0.5)
			(max_length 1)
			(best_width_ratio 1)
			(max_width 2)
			(curved_edges yes)
			(filter_ratio 0.9)
			(enabled no)
			(allow_two_segments yes)
			(prefer_zone_connections yes)
		)
		(net 1)
	)
	(via
		(at 135.95 95.1)
		(size 0.5)
		(drill 0.2)
		(layers "F.Cu" "B.Cu")
		(remove_unused_layers yes)
		(keep_end_layers yes)
		(free yes)
		(zone_layer_connections "In1.Cu" "In2.Cu")
		(teardrops
			(best_length_ratio 0.5)
			(max_length 1)
			(best_width_ratio 1)
			(max_width 2)
			(curved_edges yes)
			(filter_ratio 0.9)
			(enabled no)
			(allow_two_segments yes)
			(prefer_zone_connections yes)
		)
		(net 1)
	)
	(via
		(at 135.95 97.6)
		(size 0.5)
		(drill 0.2)
		(layers "F.Cu" "B.Cu")
		(remove_unused_layers yes)
		(keep_end_layers yes)
		(free yes)
		(zone_layer_connections "In1.Cu" "In2.Cu")
		(teardrops
			(best_length_ratio 0.5)
			(max_length 1)
			(best_width_ratio 1)
			(max_width 2)
			(curved_edges yes)
			(filter_ratio 0.9)
			(enabled no)
			(allow_two_segments yes)
			(prefer_zone_connections yes)
		)
		(net 1)
	)
	(via
		(at 135.95 64.6)
		(size 0.5)
		(drill 0.2)
		(layers "F.Cu" "B.Cu")
		(remove_unused_layers yes)
		(keep_end_layers yes)
		(free yes)
		(zone_layer_connections "In1.Cu" "In2.Cu")
		(teardrops
			(best_length_ratio 0.5)
			(max_length 1)
			(best_width_ratio 1)
			(max_width 2)
			(curved_edges yes)
			(filter_ratio 0.9)
			(enabled no)
			(allow_two_segments yes)
			(prefer_zone_connections yes)
		)
		(net 1)
	)
	(via
		(at 135.95 57.1)
		(size 0.5)
		(drill 0.2)
		(layers "F.Cu" "B.Cu")
		(remove_unused_layers yes)
		(keep_end_layers yes)
		(free yes)
		(zone_layer_connections "In1.Cu" "In2.Cu")
		(teardrops
			(best_length_ratio 0.5)
			(max_length 1)
			(best_width_ratio 1)
			(max_width 2)
			(curved_edges yes)
			(filter_ratio 0.9)
			(enabled no)
			(allow_two_segments yes)
			(prefer_zone_connections yes)
		)
		(net 1)
	)
	(via
		(at 150.390512 127.03)
		(size 0.5)
		(drill 0.2)
		(layers "F.Cu" "B.Cu")
		(remove_unused_layers yes)
		(keep_end_layers yes)
		(zone_layer_connections "In1.Cu" "In2.Cu")
		(teardrops
			(best_length_ratio 0.5)
			(max_length 1)
			(best_width_ratio 1)
			(max_width 2)
			(curved_edges yes)
			(filter_ratio 0.9)
			(enabled no)
			(allow_two_segments yes)
			(prefer_zone_connections no)
		)
		(net 1)
	)
	(via
		(at 150.89 95.57)
		(size 0.5)
		(drill 0.2)
		(layers "F.Cu" "B.Cu")
		(remove_unused_layers yes)
		(keep_end_layers yes)
		(zone_layer_connections "In1.Cu" "In2.Cu")
		(net 1)
	)
	(via
		(at 156.3 120.329343)
		(size 0.5)
		(drill 0.2)
		(layers "F.Cu" "B.Cu")
		(remove_unused_layers yes)
		(keep_end_layers yes)
		(free yes)
		(zone_layer_connections "In1.Cu" "In2.Cu")
		(teardrops
			(best_length_ratio 0.5)
			(max_length 1)
			(best_width_ratio 1)
			(max_width 2)
			(curved_edges yes)
			(filter_ratio 0.9)
			(enabled no)
			(allow_two_segments yes)
			(prefer_zone_connections yes)
		)
		(net 1)
	)
	(via
		(at 147 52.8)
		(size 0.5)
		(drill 0.2)
		(layers "F.Cu" "B.Cu")
		(remove_unused_layers yes)
		(keep_end_layers yes)
		(free yes)
		(zone_layer_connections "In1.Cu" "In2.Cu")
		(teardrops
			(best_length_ratio 0.5)
			(max_length 1)
			(best_width_ratio 1)
			(max_width 2)
			(curved_edges yes)
			(filter_ratio 0.9)
			(enabled no)
			(allow_two_segments yes)
			(prefer_zone_connections yes)
		)
		(net 1)
	)
	(via
		(at 136.521256 115.893205)
		(size 0.5)
		(drill 0.2)
		(layers "F.Cu" "B.Cu")
		(remove_unused_layers yes)
		(keep_end_layers yes)
		(zone_layer_connections "In1.Cu" "In2.Cu")
		(teardrops
			(best_length_ratio 0.5)
			(max_length 1)
			(best_width_ratio 1)
			(max_width 2)
			(curved_edges yes)
			(filter_ratio 0.9)
			(enabled no)
			(allow_two_segments yes)
			(prefer_zone_connections no)
		)
		(net 1)
	)
	(via
		(at 146.314591 97.598194)
		(size 0.5)
		(drill 0.2)
		(layers "F.Cu" "B.Cu")
		(remove_unused_layers yes)
		(keep_end_layers yes)
		(zone_layer_connections "In1.Cu" "In2.Cu")
		(teardrops
			(best_length_ratio 0.5)
			(max_length 1)
			(best_width_ratio 1)
			(max_width 2)
			(curved_edges yes)
			(filter_ratio 0.9)
			(enabled no)
			(allow_two_segments yes)
			(prefer_zone_connections no)
		)
		(net 1)
	)
	(via
		(at 156.3 92.829343)
		(size 0.5)
		(drill 0.2)
		(layers "F.Cu" "B.Cu")
		(remove_unused_layers yes)
		(keep_end_layers yes)
		(free yes)
		(zone_layer_connections "In1.Cu" "In2.Cu")
		(teardrops
			(best_length_ratio 0.5)
			(max_length 1)
			(best_width_ratio 1)
			(max_width 2)
			(curved_edges yes)
			(filter_ratio 0.9)
			(enabled no)
			(allow_two_segments yes)
			(prefer_zone_connections yes)
		)
		(net 1)
	)
	(via
		(at 142.673261 92.898315)
		(size 0.5)
		(drill 0.2)
		(layers "F.Cu" "B.Cu")
		(remove_unused_layers yes)
		(keep_end_layers yes)
		(zone_layer_connections "In1.Cu" "In2.Cu")
		(teardrops
			(best_length_ratio 0.5)
			(max_length 1)
			(best_width_ratio 1)
			(max_width 2)
			(curved_edges yes)
			(filter_ratio 0.9)
			(enabled no)
			(allow_two_segments yes)
			(prefer_zone_connections yes)
		)
		(net 1)
	)
	(via
		(at 135.95 59.6)
		(size 0.5)
		(drill 0.2)
		(layers "F.Cu" "B.Cu")
		(remove_unused_layers yes)
		(keep_end_layers yes)
		(free yes)
		(zone_layer_connections "In1.Cu" "In2.Cu")
		(teardrops
			(best_length_ratio 0.5)
			(max_length 1)
			(best_width_ratio 1)
			(max_width 2)
			(curved_edges yes)
			(filter_ratio 0.9)
			(enabled no)
			(allow_two_segments yes)
			(prefer_zone_connections yes)
		)
		(net 1)
	)
	(via
		(at 147.211614 95.645223)
		(size 0.5)
		(drill 0.2)
		(layers "F.Cu" "B.Cu")
		(remove_unused_layers yes)
		(keep_end_layers yes)
		(zone_layer_connections "In1.Cu" "In2.Cu")
		(teardrops
			(best_length_ratio 0.5)
			(max_length 1)
			(best_width_ratio 1)
			(max_width 2)
			(curved_edges yes)
			(filter_ratio 0.9)
			(enabled no)
			(allow_two_segments yes)
			(prefer_zone_connections no)
		)
		(net 1)
	)
	(via
		(at 156.3 117.829343)
		(size 0.5)
		(drill 0.2)
		(layers "F.Cu" "B.Cu")
		(remove_unused_layers yes)
		(keep_end_layers yes)
		(free yes)
		(zone_layer_connections "In1.Cu" "In2.Cu")
		(teardrops
			(best_length_ratio 0.5)
			(max_length 1)
			(best_width_ratio 1)
			(max_width 2)
			(curved_edges yes)
			(filter_ratio 0.9)
			(enabled no)
			(allow_two_segments yes)
			(prefer_zone_connections yes)
		)
		(net 1)
	)
	(via
		(at 135.95 90.1)
		(size 0.5)
		(drill 0.2)
		(layers "F.Cu" "B.Cu")
		(remove_unused_layers yes)
		(keep_end_layers yes)
		(free yes)
		(zone_layer_connections "In1.Cu" "In2.Cu")
		(teardrops
			(best_length_ratio 0.5)
			(max_length 1)
			(best_width_ratio 1)
			(max_width 2)
			(curved_edges yes)
			(filter_ratio 0.9)
			(enabled no)
			(allow_two_segments yes)
			(prefer_zone_connections yes)
		)
		(net 1)
	)
	(via
		(at 151.935066 125.745589)
		(size 0.5)
		(drill 0.2)
		(layers "F.Cu" "B.Cu")
		(remove_unused_layers yes)
		(keep_end_layers yes)
		(zone_layer_connections "In1.Cu" "In2.Cu")
		(teardrops
			(best_length_ratio 0.5)
			(max_length 1)
			(best_width_ratio 1)
			(max_width 2)
			(curved_edges yes)
			(filter_ratio 0.9)
			(enabled no)
			(allow_two_segments yes)
			(prefer_zone_connections no)
		)
		(net 1)
	)
	(via
		(at 148.879965 127.03)
		(size 0.5)
		(drill 0.2)
		(layers "F.Cu" "B.Cu")
		(remove_unused_layers yes)
		(keep_end_layers yes)
		(zone_layer_connections "In1.Cu" "In2.Cu")
		(teardrops
			(best_length_ratio 0.5)
			(max_length 1)
			(best_width_ratio 1)
			(max_width 2)
			(curved_edges yes)
			(filter_ratio 0.9)
			(enabled no)
			(allow_two_segments yes)
			(prefer_zone_connections no)
		)
		(net 1)
	)
	(via
		(at 136.04 120.86)
		(size 0.5)
		(drill 0.2)
		(layers "F.Cu" "B.Cu")
		(remove_unused_layers yes)
		(keep_end_layers yes)
		(zone_layer_connections "In1.Cu" "In2.Cu")
		(net 1)
	)
	(via
		(at 147.901352 93.469591)
		(size 0.5)
		(drill 0.2)
		(layers "F.Cu" "B.Cu")
		(remove_unused_layers yes)
		(keep_end_layers yes)
		(zone_layer_connections "In1.Cu" "In2.Cu")
		(net 1)
	)
	(via
		(at 142.867838 123.146674)
		(size 0.5)
		(drill 0.2)
		(layers "F.Cu" "B.Cu")
		(remove_unused_layers yes)
		(keep_end_layers yes)
		(zone_layer_connections "In1.Cu" "In2.Cu")
		(teardrops
			(best_length_ratio 0.5)
			(max_length 1)
			(best_width_ratio 1)
			(max_width 2)
			(curved_edges yes)
			(filter_ratio 0.9)
			(enabled no)
			(allow_two_segments yes)
			(prefer_zone_connections no)
		)
		(net 1)
	)
	(via
		(at 135.95 80.1)
		(size 0.5)
		(drill 0.2)
		(layers "F.Cu" "B.Cu")
		(remove_unused_layers yes)
		(keep_end_layers yes)
		(free yes)
		(zone_layer_connections "In1.Cu" "In2.Cu")
		(teardrops
			(best_length_ratio 0.5)
			(max_length 1)
			(best_width_ratio 1)
			(max_width 2)
			(curved_edges yes)
			(filter_ratio 0.9)
			(enabled no)
			(allow_two_segments yes)
			(prefer_zone_connections yes)
		)
		(net 1)
	)
	(via
		(at 156.3 71.5)
		(size 0.5)
		(drill 0.2)
		(layers "F.Cu" "B.Cu")
		(remove_unused_layers yes)
		(keep_end_layers yes)
		(free yes)
		(zone_layer_connections "In1.Cu" "In2.Cu")
		(teardrops
			(best_length_ratio 0.5)
			(max_length 1)
			(best_width_ratio 1)
			(max_width 2)
			(curved_edges yes)
			(filter_ratio 0.9)
			(enabled no)
			(allow_two_segments yes)
			(prefer_zone_connections yes)
		)
		(net 1)
	)
	(via
		(at 144.271 93.647847)
		(size 0.5)
		(drill 0.2)
		(layers "F.Cu" "B.Cu")
		(remove_unused_layers yes)
		(keep_end_layers yes)
		(zone_layer_connections "In1.Cu" "In2.Cu")
		(teardrops
			(best_length_ratio 0.5)
			(max_length 1)
			(best_width_ratio 1)
			(max_width 2)
			(curved_edges yes)
			(filter_ratio 0.9)
			(enabled no)
			(allow_two_segments yes)
			(prefer_zone_connections yes)
		)
		(net 1)
	)
	(via
		(at 141.138396 126.981681)
		(size 0.5)
		(drill 0.2)
		(layers "F.Cu" "B.Cu")
		(remove_unused_layers yes)
		(keep_end_layers yes)
		(zone_layer_connections "In1.Cu" "In2.Cu")
		(teardrops
			(best_length_ratio 0.5)
			(max_length 1)
			(best_width_ratio 1)
			(max_width 2)
			(curved_edges yes)
			(filter_ratio 0.9)
			(enabled no)
			(allow_two_segments yes)
			(prefer_zone_connections no)
		)
		(net 1)
	)
	(via
		(at 156.3 122.829343)
		(size 0.5)
		(drill 0.2)
		(layers "F.Cu" "B.Cu")
		(remove_unused_layers yes)
		(keep_end_layers yes)
		(free yes)
		(zone_layer_connections "In1.Cu" "In2.Cu")
		(teardrops
			(best_length_ratio 0.5)
			(max_length 1)
			(best_width_ratio 1)
			(max_width 2)
			(curved_edges yes)
			(filter_ratio 0.9)
			(enabled no)
			(allow_two_segments yes)
			(prefer_zone_connections yes)
		)
		(net 1)
	)
	(via
		(at 154.55 51.4)
		(size 0.5)
		(drill 0.2)
		(layers "F.Cu" "B.Cu")
		(remove_unused_layers yes)
		(keep_end_layers yes)
		(free yes)
		(zone_layer_connections "In1.Cu" "In2.Cu")
		(teardrops
			(best_length_ratio 0.5)
			(max_length 1)
			(best_width_ratio 1)
			(max_width 2)
			(curved_edges yes)
			(filter_ratio 0.9)
			(enabled no)
			(allow_two_segments yes)
			(prefer_zone_connections yes)
		)
		(net 1)
	)
	(via
		(at 141.677041 97.192904)
		(size 0.5)
		(drill 0.2)
		(layers "F.Cu" "B.Cu")
		(remove_unused_layers yes)
		(keep_end_layers yes)
		(zone_layer_connections "In1.Cu" "In2.Cu")
		(teardrops
			(best_length_ratio 0.5)
			(max_length 1)
			(best_width_ratio 1)
			(max_width 2)
			(curved_edges yes)
			(filter_ratio 0.9)
			(enabled no)
			(allow_two_segments yes)
			(prefer_zone_connections no)
		)
		(net 1)
	)
	(via
		(at 156.3 67.15)
		(size 0.5)
		(drill 0.2)
		(layers "F.Cu" "B.Cu")
		(remove_unused_layers yes)
		(keep_end_layers yes)
		(free yes)
		(zone_layer_connections "In1.Cu" "In2.Cu")
		(teardrops
			(best_length_ratio 0.5)
			(max_length 1)
			(best_width_ratio 1)
			(max_width 2)
			(curved_edges yes)
			(filter_ratio 0.9)
			(enabled no)
			(allow_two_segments yes)
			(prefer_zone_connections yes)
		)
		(net 1)
	)
	(via
		(at 156.3 77.829343)
		(size 0.5)
		(drill 0.2)
		(layers "F.Cu" "B.Cu")
		(remove_unused_layers yes)
		(keep_end_layers yes)
		(free yes)
		(zone_layer_connections "In1.Cu" "In2.Cu")
		(teardrops
			(best_length_ratio 0.5)
			(max_length 1)
			(best_width_ratio 1)
			(max_width 2)
			(curved_edges yes)
			(filter_ratio 0.9)
			(enabled no)
			(allow_two_segments yes)
			(prefer_zone_connections yes)
		)
		(net 1)
	)
	(via
		(at 148.4 51.16)
		(size 0.5)
		(drill 0.2)
		(layers "F.Cu" "B.Cu")
		(remove_unused_layers yes)
		(keep_end_layers yes)
		(free yes)
		(zone_layer_connections "In1.Cu" "In2.Cu")
		(teardrops
			(best_length_ratio 0.5)
			(max_length 1)
			(best_width_ratio 1)
			(max_width 2)
			(curved_edges yes)
			(filter_ratio 0.9)
			(enabled no)
			(allow_two_segments yes)
			(prefer_zone_connections yes)
		)
		(net 1)
	)
	(via
		(at 144 52)
		(size 0.5)
		(drill 0.2)
		(layers "F.Cu" "B.Cu")
		(remove_unused_layers yes)
		(keep_end_layers yes)
		(free yes)
		(zone_layer_connections "In1.Cu" "In2.Cu")
		(teardrops
			(best_length_ratio 0.5)
			(max_length 1)
			(best_width_ratio 1)
			(max_width 2)
			(curved_edges yes)
			(filter_ratio 0.9)
			(enabled no)
			(allow_two_segments yes)
			(prefer_zone_connections yes)
		)
		(net 1)
	)
	(via
		(at 135.95 52.1)
		(size 0.5)
		(drill 0.2)
		(layers "F.Cu" "B.Cu")
		(remove_unused_layers yes)
		(keep_end_layers yes)
		(free yes)
		(zone_layer_connections "In1.Cu" "In2.Cu")
		(teardrops
			(best_length_ratio 0.5)
			(max_length 1)
			(best_width_ratio 1)
			(max_width 2)
			(curved_edges yes)
			(filter_ratio 0.9)
			(enabled no)
			(allow_two_segments yes)
			(prefer_zone_connections yes)
		)
		(net 1)
	)
	(via
		(at 156.3 59.65)
		(size 0.5)
		(drill 0.2)
		(layers "F.Cu" "B.Cu")
		(remove_unused_layers yes)
		(keep_end_layers yes)
		(free yes)
		(zone_layer_connections "In1.Cu" "In2.Cu")
		(teardrops
			(best_length_ratio 0.5)
			(max_length 1)
			(best_width_ratio 1)
			(max_width 2)
			(curved_edges yes)
			(filter_ratio 0.9)
			(enabled no)
			(allow_two_segments yes)
			(prefer_zone_connections yes)
		)
		(net 1)
	)
	(via
		(at 135.95 120.1)
		(size 0.5)
		(drill 0.2)
		(layers "F.Cu" "B.Cu")
		(remove_unused_layers yes)
		(keep_end_layers yes)
		(free yes)
		(zone_layer_connections "In1.Cu" "In2.Cu")
		(teardrops
			(best_length_ratio 0.5)
			(max_length 1)
			(best_width_ratio 1)
			(max_width 2)
			(curved_edges yes)
			(filter_ratio 0.9)
			(enabled no)
			(allow_two_segments yes)
			(prefer_zone_connections yes)
		)
		(net 1)
	)
	(via
		(at 143.6 51.17)
		(size 0.5)
		(drill 0.2)
		(layers "F.Cu" "B.Cu")
		(remove_unused_layers yes)
		(keep_end_layers yes)
		(free yes)
		(zone_layer_connections "In1.Cu" "In2.Cu")
		(teardrops
			(best_length_ratio 0.5)
			(max_length 1)
			(best_width_ratio 1)
			(max_width 2)
			(curved_edges yes)
			(filter_ratio 0.9)
			(enabled no)
			(allow_two_segments yes)
			(prefer_zone_connections yes)
		)
		(net 1)
	)
	(via
		(at 143.7 70.6)
		(size 0.5)
		(drill 0.2)
		(layers "F.Cu" "B.Cu")
		(remove_unused_layers yes)
		(keep_end_layers yes)
		(free yes)
		(zone_layer_connections "In1.Cu" "In2.Cu")
		(teardrops
			(best_length_ratio 0.5)
			(max_length 1)
			(best_width_ratio 1)
			(max_width 2)
			(curved_edges yes)
			(filter_ratio 0.9)
			(enabled no)
			(allow_two_segments yes)
			(prefer_zone_connections yes)
		)
		(net 1)
	)
	(via
		(at 135.95 87.6)
		(size 0.5)
		(drill 0.2)
		(layers "F.Cu" "B.Cu")
		(remove_unused_layers yes)
		(keep_end_layers yes)
		(free yes)
		(zone_layer_connections "In1.Cu" "In2.Cu")
		(teardrops
			(best_length_ratio 0.5)
			(max_length 1)
			(best_width_ratio 1)
			(max_width 2)
			(curved_edges yes)
			(filter_ratio 0.9)
			(enabled no)
			(allow_two_segments yes)
			(prefer_zone_connections yes)
		)
		(net 1)
	)
	(via
		(at 146 53)
		(size 0.5)
		(drill 0.2)
		(layers "F.Cu" "B.Cu")
		(remove_unused_layers yes)
		(keep_end_layers yes)
		(free yes)
		(zone_layer_connections "In1.Cu" "In2.Cu")
		(teardrops
			(best_length_ratio 0.5)
			(max_length 1)
			(best_width_ratio 1)
			(max_width 2)
			(curved_edges yes)
			(filter_ratio 0.9)
			(enabled no)
			(allow_two_segments yes)
			(prefer_zone_connections yes)
		)
		(net 1)
	)
	(via
		(at 148.6 70.6)
		(size 0.5)
		(drill 0.2)
		(layers "F.Cu" "B.Cu")
		(remove_unused_layers yes)
		(keep_end_layers yes)
		(free yes)
		(zone_layer_connections "In1.Cu" "In2.Cu")
		(teardrops
			(best_length_ratio 0.5)
			(max_length 1)
			(best_width_ratio 1)
			(max_width 2)
			(curved_edges yes)
			(filter_ratio 0.9)
			(enabled no)
			(allow_two_segments yes)
			(prefer_zone_connections yes)
		)
		(net 1)
	)
	(via
		(at 148 52)
		(size 0.5)
		(drill 0.2)
		(layers "F.Cu" "B.Cu")
		(remove_unused_layers yes)
		(keep_end_layers yes)
		(free yes)
		(zone_layer_connections "In1.Cu" "In2.Cu")
		(teardrops
			(best_length_ratio 0.5)
			(max_length 1)
			(best_width_ratio 1)
			(max_width 2)
			(curved_edges yes)
			(filter_ratio 0.9)
			(enabled no)
			(allow_two_segments yes)
			(prefer_zone_connections yes)
		)
		(net 1)
	)
	(via
		(at 145.91 127.03)
		(size 0.5)
		(drill 0.2)
		(layers "F.Cu" "B.Cu")
		(remove_unused_layers yes)
		(keep_end_layers yes)
		(zone_layer_connections "In1.Cu" "In2.Cu")
		(teardrops
			(best_length_ratio 0.5)
			(max_length 1)
			(best_width_ratio 1)
			(max_width 2)
			(curved_edges yes)
			(filter_ratio 0.9)
			(enabled no)
			(allow_two_segments yes)
			(prefer_zone_connections yes)
		)
		(net 1)
	)
	(via
		(at 156.3 87.829343)
		(size 0.5)
		(drill 0.2)
		(layers "F.Cu" "B.Cu")
		(remove_unused_layers yes)
		(keep_end_layers yes)
		(free yes)
		(zone_layer_connections "In1.Cu" "In2.Cu")
		(teardrops
			(best_length_ratio 0.5)
			(max_length 1)
			(best_width_ratio 1)
			(max_width 2)
			(curved_edges yes)
			(filter_ratio 0.9)
			(enabled no)
			(allow_two_segments yes)
			(prefer_zone_connections yes)
		)
		(net 1)
	)
	(via
		(at 153.327041 93.742904)
		(size 0.5)
		(drill 0.2)
		(layers "F.Cu" "B.Cu")
		(remove_unused_layers yes)
		(keep_end_layers yes)
		(zone_layer_connections "In1.Cu" "In2.Cu")
		(teardrops
			(best_length_ratio 0.5)
			(max_length 1)
			(best_width_ratio 1)
			(max_width 2)
			(curved_edges yes)
			(filter_ratio 0.9)
			(enabled no)
			(allow_two_segments yes)
			(prefer_zone_connections no)
		)
		(net 1)
	)
	(via
		(at 156.3 100.329343)
		(size 0.5)
		(drill 0.2)
		(layers "F.Cu" "B.Cu")
		(remove_unused_layers yes)
		(keep_end_layers yes)
		(free yes)
		(zone_layer_connections "In1.Cu" "In2.Cu")
		(teardrops
			(best_length_ratio 0.5)
			(max_length 1)
			(best_width_ratio 1)
			(max_width 2)
			(curved_edges yes)
			(filter_ratio 0.9)
			(enabled no)
			(allow_two_segments yes)
			(prefer_zone_connections yes)
		)
		(net 1)
	)
	(via
		(at 156.125 125.825)
		(size 0.5)
		(drill 0.2)
		(layers "F.Cu" "B.Cu")
		(remove_unused_layers yes)
		(keep_end_layers yes)
		(free yes)
		(zone_layer_connections "In1.Cu" "In2.Cu")
		(teardrops
			(best_length_ratio 0.5)
			(max_length 1)
			(best_width_ratio 1)
			(max_width 2)
			(curved_edges yes)
			(filter_ratio 0.9)
			(enabled no)
			(allow_two_segments yes)
			(prefer_zone_connections yes)
		)
		(net 1)
	)
	(via
		(at 156.3 110.329343)
		(size 0.5)
		(drill 0.2)
		(layers "F.Cu" "B.Cu")
		(remove_unused_layers yes)
		(keep_end_layers yes)
		(free yes)
		(zone_layer_connections "In1.Cu" "In2.Cu")
		(teardrops
			(best_length_ratio 0.5)
			(max_length 1)
			(best_width_ratio 1)
			(max_width 2)
			(curved_edges yes)
			(filter_ratio 0.9)
			(enabled no)
			(allow_two_segments yes)
			(prefer_zone_connections yes)
		)
		(net 1)
	)
	(via
		(at 140.277041 99.492904)
		(size 0.5)
		(drill 0.2)
		(layers "F.Cu" "B.Cu")
		(remove_unused_layers yes)
		(keep_end_layers yes)
		(zone_layer_connections "In1.Cu" "In2.Cu")
		(teardrops
			(best_length_ratio 0.5)
			(max_length 1)
			(best_width_ratio 1)
			(max_width 2)
			(curved_edges yes)
			(filter_ratio 0.9)
			(enabled no)
			(allow_two_segments yes)
			(prefer_zone_connections no)
		)
		(net 1)
	)
	(via
		(at 156.3 107.829343)
		(size 0.5)
		(drill 0.2)
		(layers "F.Cu" "B.Cu")
		(remove_unused_layers yes)
		(keep_end_layers yes)
		(free yes)
		(zone_layer_connections "In1.Cu" "In2.Cu")
		(teardrops
			(best_length_ratio 0.5)
			(max_length 1)
			(best_width_ratio 1)
			(max_width 2)
			(curved_edges yes)
			(filter_ratio 0.9)
			(enabled no)
			(allow_two_segments yes)
			(prefer_zone_connections yes)
		)
		(net 1)
	)
	(via
		(at 135.95 100.1)
		(size 0.5)
		(drill 0.2)
		(layers "F.Cu" "B.Cu")
		(remove_unused_layers yes)
		(keep_end_layers yes)
		(free yes)
		(zone_layer_connections "In1.Cu" "In2.Cu")
		(teardrops
			(best_length_ratio 0.5)
			(max_length 1)
			(best_width_ratio 1)
			(max_width 2)
			(curved_edges yes)
			(filter_ratio 0.9)
			(enabled no)
			(allow_two_segments yes)
			(prefer_zone_connections yes)
		)
		(net 1)
	)
	(via
		(at 152.05 51.4)
		(size 0.5)
		(drill 0.2)
		(layers "F.Cu" "B.Cu")
		(remove_unused_layers yes)
		(keep_end_layers yes)
		(free yes)
		(zone_layer_connections "In1.Cu" "In2.Cu")
		(teardrops
			(best_length_ratio 0.5)
			(max_length 1)
			(best_width_ratio 1)
			(max_width 2)
			(curved_edges yes)
			(filter_ratio 0.9)
			(enabled no)
			(allow_two_segments yes)
			(prefer_zone_connections yes)
		)
		(net 1)
	)
	(via
		(at 144.412023 127.03)
		(size 0.5)
		(drill 0.2)
		(layers "F.Cu" "B.Cu")
		(remove_unused_layers yes)
		(keep_end_layers yes)
		(zone_layer_connections "In1.Cu" "In2.Cu")
		(teardrops
			(best_length_ratio 0.5)
			(max_length 1)
			(best_width_ratio 1)
			(max_width 2)
			(curved_edges yes)
			(filter_ratio 0.9)
			(enabled no)
			(allow_two_segments yes)
			(prefer_zone_connections yes)
		)
		(net 1)
	)
	(via
		(at 147.816435 97.498209)
		(size 0.5)
		(drill 0.2)
		(layers "F.Cu" "B.Cu")
		(remove_unused_layers yes)
		(keep_end_layers yes)
		(zone_layer_connections "In1.Cu" "In2.Cu")
		(teardrops
			(best_length_ratio 0.5)
			(max_length 1)
			(best_width_ratio 1)
			(max_width 2)
			(curved_edges yes)
			(filter_ratio 0.9)
			(enabled no)
			(allow_two_segments yes)
			(prefer_zone_connections no)
		)
		(net 1)
	)
	(via
		(at 151.896167 126.475)
		(size 0.5)
		(drill 0.2)
		(layers "F.Cu" "B.Cu")
		(remove_unused_layers yes)
		(keep_end_layers yes)
		(zone_layer_connections "In1.Cu" "In2.Cu")
		(teardrops
			(best_length_ratio 0.5)
			(max_length 1)
			(best_width_ratio 1)
			(max_width 2)
			(curved_edges yes)
			(filter_ratio 0.9)
			(enabled no)
			(allow_two_segments yes)
			(prefer_zone_connections no)
		)
		(net 1)
	)
	(via
		(at 135.95 62.1)
		(size 0.5)
		(drill 0.2)
		(layers "F.Cu" "B.Cu")
		(remove_unused_layers yes)
		(keep_end_layers yes)
		(free yes)
		(zone_layer_connections "In1.Cu" "In2.Cu")
		(teardrops
			(best_length_ratio 0.5)
			(max_length 1)
			(best_width_ratio 1)
			(max_width 2)
			(curved_edges yes)
			(filter_ratio 0.9)
			(enabled no)
			(allow_two_segments yes)
			(prefer_zone_connections yes)
		)
		(net 1)
	)
	(via
		(at 135.95 85.1)
		(size 0.5)
		(drill 0.2)
		(layers "F.Cu" "B.Cu")
		(remove_unused_layers yes)
		(keep_end_layers yes)
		(free yes)
		(zone_layer_connections "In1.Cu" "In2.Cu")
		(teardrops
			(best_length_ratio 0.5)
			(max_length 1)
			(best_width_ratio 1)
			(max_width 2)
			(curved_edges yes)
			(filter_ratio 0.9)
			(enabled no)
			(allow_two_segments yes)
			(prefer_zone_connections yes)
		)
		(net 1)
	)
	(via
		(at 150.86 97.16)
		(size 0.5)
		(drill 0.2)
		(layers "F.Cu" "B.Cu")
		(remove_unused_layers yes)
		(keep_end_layers yes)
		(zone_layer_connections "In1.Cu" "In2.Cu")
		(teardrops
			(best_length_ratio 0.5)
			(max_length 1)
			(best_width_ratio 1)
			(max_width 2)
			(curved_edges yes)
			(filter_ratio 0.9)
			(enabled no)
			(allow_two_segments yes)
			(prefer_zone_connections no)
		)
		(net 1)
	)
	(via
		(at 148.766838 123.037984)
		(size 0.5)
		(drill 0.2)
		(layers "F.Cu" "B.Cu")
		(remove_unused_layers yes)
		(keep_end_layers yes)
		(zone_layer_connections "In1.Cu" "In2.Cu")
		(teardrops
			(best_length_ratio 0.5)
			(max_length 1)
			(best_width_ratio 1)
			(max_width 2)
			(curved_edges yes)
			(filter_ratio 0.9)
			(enabled no)
			(allow_two_segments yes)
			(prefer_zone_connections no)
		)
		(net 1)
	)
	(via
		(at 140.4 95.05)
		(size 0.5)
		(drill 0.2)
		(layers "F.Cu" "B.Cu")
		(remove_unused_layers yes)
		(keep_end_layers yes)
		(zone_layer_connections "In1.Cu" "In2.Cu")
		(teardrops
			(best_length_ratio 0.5)
			(max_length 1)
			(best_width_ratio 1)
			(max_width 2)
			(curved_edges yes)
			(filter_ratio 0.9)
			(enabled no)
			(allow_two_segments yes)
			(prefer_zone_connections yes)
		)
		(net 1)
	)
	(via
		(at 148.729071 95.643685)
		(size 0.5)
		(drill 0.2)
		(layers "F.Cu" "B.Cu")
		(remove_unused_layers yes)
		(keep_end_layers yes)
		(zone_layer_connections "In1.Cu" "In2.Cu")
		(teardrops
			(best_length_ratio 0.5)
			(max_length 1)
			(best_width_ratio 1)
			(max_width 2)
			(curved_edges yes)
			(filter_ratio 0.9)
			(enabled no)
			(allow_two_segments yes)
			(prefer_zone_connections no)
		)
		(net 1)
	)
	(via
		(at 142.638981 93.601019)
		(size 0.5)
		(drill 0.2)
		(layers "F.Cu" "B.Cu")
		(remove_unused_layers yes)
		(keep_end_layers yes)
		(zone_layer_connections "In1.Cu" "In2.Cu")
		(teardrops
			(best_length_ratio 0.5)
			(max_length 1)
			(best_width_ratio 1)
			(max_width 2)
			(curved_edges yes)
			(filter_ratio 0.9)
			(enabled no)
			(allow_two_segments yes)
			(prefer_zone_connections yes)
		)
		(net 1)
	)
	(via
		(at 151.3 71.5)
		(size 0.5)
		(drill 0.2)
		(layers "F.Cu" "B.Cu")
		(remove_unused_layers yes)
		(keep_end_layers yes)
		(free yes)
		(zone_layer_connections "In1.Cu" "In2.Cu")
		(teardrops
			(best_length_ratio 0.5)
			(max_length 1)
			(best_width_ratio 1)
			(max_width 2)
			(curved_edges yes)
			(filter_ratio 0.9)
			(enabled no)
			(allow_two_segments yes)
			(prefer_zone_connections yes)
		)
		(net 1)
	)
	(via
		(at 153.334595 126.999609)
		(size 0.5)
		(drill 0.2)
		(layers "F.Cu" "B.Cu")
		(remove_unused_layers yes)
		(keep_end_layers yes)
		(zone_layer_connections "In1.Cu" "In2.Cu")
		(teardrops
			(best_length_ratio 0.5)
			(max_length 1)
			(best_width_ratio 1)
			(max_width 2)
			(curved_edges yes)
			(filter_ratio 0.9)
			(enabled no)
			(allow_two_segments yes)
			(prefer_zone_connections no)
		)
		(net 1)
	)
	(via
		(at 147.50083 92.964936)
		(size 0.5)
		(drill 0.2)
		(layers "F.Cu" "B.Cu")
		(remove_unused_layers yes)
		(keep_end_layers yes)
		(zone_layer_connections "In1.Cu" "In2.Cu")
		(teardrops
			(best_length_ratio 0.5)
			(max_length 1)
			(best_width_ratio 1)
			(max_width 2)
			(curved_edges yes)
			(filter_ratio 0.9)
			(enabled no)
			(allow_two_segments yes)
			(prefer_zone_connections no)
		)
		(net 1)
	)
	(via
		(at 135.95 82.6)
		(size 0.5)
		(drill 0.2)
		(layers "F.Cu" "B.Cu")
		(remove_unused_layers yes)
		(keep_end_layers yes)
		(free yes)
		(zone_layer_connections "In1.Cu" "In2.Cu")
		(teardrops
			(best_length_ratio 0.5)
			(max_length 1)
			(best_width_ratio 1)
			(max_width 2)
			(curved_edges yes)
			(filter_ratio 0.9)
			(enabled no)
			(allow_two_segments yes)
			(prefer_zone_connections yes)
		)
		(net 1)
	)
	(via
		(at 155.654206 124.770221)
		(size 0.5)
		(drill 0.2)
		(layers "F.Cu" "B.Cu")
		(remove_unused_layers yes)
		(keep_end_layers yes)
		(zone_layer_connections "In1.Cu" "In2.Cu")
		(net 1)
	)
	(via
		(at 135.95 77.6)
		(size 0.5)
		(drill 0.2)
		(layers "F.Cu" "B.Cu")
		(remove_unused_layers yes)
		(keep_end_layers yes)
		(free yes)
		(zone_layer_connections "In1.Cu" "In2.Cu")
		(teardrops
			(best_length_ratio 0.5)
			(max_length 1)
			(best_width_ratio 1)
			(max_width 2)
			(curved_edges yes)
			(filter_ratio 0.9)
			(enabled no)
			(allow_two_segments yes)
			(prefer_zone_connections yes)
		)
		(net 1)
	)
	(via
		(at 146.15 70.6)
		(size 5.5)
		(drill 3.5)
		(layers "F.Cu" "B.Cu")
		(remove_unused_layers yes)
		(keep_end_layers yes)
		(locked yes)
		(zone_layer_connections "In1.Cu" "In2.Cu")
		(tenting none)
		(teardrops
			(best_length_ratio 0.5)
			(max_length 1)
			(best_width_ratio 1)
			(max_width 2)
			(curved_edges yes)
			(filter_ratio 0.9)
			(enabled no)
			(allow_two_segments yes)
			(prefer_zone_connections no)
		)
		(net 1)
	)
	(via
		(at 145.13 97.4)
		(size 0.5)
		(drill 0.2)
		(layers "F.Cu" "B.Cu")
		(remove_unused_layers yes)
		(keep_end_layers yes)
		(zone_layer_connections "In1.Cu" "In2.Cu")
		(teardrops
			(best_length_ratio 0.5)
			(max_length 1)
			(best_width_ratio 1)
			(max_width 2)
			(curved_edges yes)
			(filter_ratio 0.9)
			(enabled no)
			(allow_two_segments yes)
			(prefer_zone_connections no)
		)
		(net 1)
	)
	(via
		(at 140.95 71.5)
		(size 0.5)
		(drill 0.2)
		(layers "F.Cu" "B.Cu")
		(remove_unused_layers yes)
		(keep_end_layers yes)
		(free yes)
		(zone_layer_connections "In1.Cu" "In2.Cu")
		(teardrops
			(best_length_ratio 0.5)
			(max_length 1)
			(best_width_ratio 1)
			(max_width 2)
			(curved_edges yes)
			(filter_ratio 0.9)
			(enabled no)
			(allow_two_segments yes)
			(prefer_zone_connections yes)
		)
		(net 1)
	)
	(via
		(at 141.17 95.6)
		(size 0.5)
		(drill 0.2)
		(layers "F.Cu" "B.Cu")
		(remove_unused_layers yes)
		(keep_end_layers yes)
		(zone_layer_connections "In1.Cu" "In2.Cu")
		(teardrops
			(best_length_ratio 0.5)
			(max_length 1)
			(best_width_ratio 1)
			(max_width 2)
			(curved_edges yes)
			(filter_ratio 0.9)
			(enabled no)
			(allow_two_segments yes)
			(prefer_zone_connections no)
		)
		(net 1)
	)
	(via
		(at 138.45 71.5)
		(size 0.5)
		(drill 0.2)
		(layers "F.Cu" "B.Cu")
		(remove_unused_layers yes)
		(keep_end_layers yes)
		(free yes)
		(zone_layer_connections "In1.Cu" "In2.Cu")
		(teardrops
			(best_length_ratio 0.5)
			(max_length 1)
			(best_width_ratio 1)
			(max_width 2)
			(curved_edges yes)
			(filter_ratio 0.9)
			(enabled no)
			(allow_two_segments yes)
			(prefer_zone_connections yes)
		)
		(net 1)
	)
	(via
		(at 135.95 110.1)
		(size 0.5)
		(drill 0.2)
		(layers "F.Cu" "B.Cu")
		(remove_unused_layers yes)
		(keep_end_layers yes)
		(free yes)
		(zone_layer_connections "In1.Cu" "In2.Cu")
		(teardrops
			(best_length_ratio 0.5)
			(max_length 1)
			(best_width_ratio 1)
			(max_width 2)
			(curved_edges yes)
			(filter_ratio 0.9)
			(enabled no)
			(allow_two_segments yes)
			(prefer_zone_connections yes)
		)
		(net 1)
	)
	(via
		(at 135.95 69.6)
		(size 0.5)
		(drill 0.2)
		(layers "F.Cu" "B.Cu")
		(remove_unused_layers yes)
		(keep_end_layers yes)
		(free yes)
		(zone_layer_connections "In1.Cu" "In2.Cu")
		(teardrops
			(best_length_ratio 0.5)
			(max_length 1)
			(best_width_ratio 1)
			(max_width 2)
			(curved_edges yes)
			(filter_ratio 0.9)
			(enabled no)
			(allow_two_segments yes)
			(prefer_zone_connections yes)
		)
		(net 1)
	)
	(via
		(at 135.95 112.6)
		(size 0.5)
		(drill 0.2)
		(layers "F.Cu" "B.Cu")
		(remove_unused_layers yes)
		(keep_end_layers yes)
		(free yes)
		(zone_layer_connections "In1.Cu" "In2.Cu")
		(teardrops
			(best_length_ratio 0.5)
			(max_length 1)
			(best_width_ratio 1)
			(max_width 2)
			(curved_edges yes)
			(filter_ratio 0.9)
			(enabled no)
			(allow_two_segments yes)
			(prefer_zone_connections yes)
		)
		(net 1)
	)
	(via
		(at 148.627305 92.601008)
		(size 0.5)
		(drill 0.2)
		(layers "F.Cu" "B.Cu")
		(remove_unused_layers yes)
		(keep_end_layers yes)
		(free yes)
		(zone_layer_connections "In1.Cu" "In2.Cu")
		(teardrops
			(best_length_ratio 0.5)
			(max_length 1)
			(best_width_ratio 1)
			(max_width 2)
			(curved_edges yes)
			(filter_ratio 0.9)
			(enabled no)
			(allow_two_segments yes)
			(prefer_zone_connections no)
		)
		(net 1)
	)
	(via
		(at 156.3 82.829343)
		(size 0.5)
		(drill 0.2)
		(layers "F.Cu" "B.Cu")
		(remove_unused_layers yes)
		(keep_end_layers yes)
		(free yes)
		(zone_layer_connections "In1.Cu" "In2.Cu")
		(teardrops
			(best_length_ratio 0.5)
			(max_length 1)
			(best_width_ratio 1)
			(max_width 2)
			(curved_edges yes)
			(filter_ratio 0.9)
			(enabled no)
			(allow_two_segments yes)
			(prefer_zone_connections yes)
		)
		(net 1)
	)
	(via
		(at 136.14 123.71)
		(size 0.5)
		(drill 0.2)
		(layers "F.Cu" "B.Cu")
		(remove_unused_layers yes)
		(keep_end_layers yes)
		(zone_layer_connections "In1.Cu" "In2.Cu")
		(net 1)
	)
	(via
		(at 135.95 75.1)
		(size 0.5)
		(drill 0.2)
		(layers "F.Cu" "B.Cu")
		(remove_unused_layers yes)
		(keep_end_layers yes)
		(free yes)
		(zone_layer_connections "In1.Cu" "In2.Cu")
		(teardrops
			(best_length_ratio 0.5)
			(max_length 1)
			(best_width_ratio 1)
			(max_width 2)
			(curved_edges yes)
			(filter_ratio 0.9)
			(enabled no)
			(allow_two_segments yes)
			(prefer_zone_connections yes)
		)
		(net 1)
	)
	(via
		(at 142.8425 126.0425)
		(size 0.5)
		(drill 0.2)
		(layers "F.Cu" "B.Cu")
		(remove_unused_layers yes)
		(keep_end_layers yes)
		(zone_layer_connections "In1.Cu" "In2.Cu")
		(teardrops
			(best_length_ratio 0.5)
			(max_length 1)
			(best_width_ratio 1)
			(max_width 2)
			(curved_edges yes)
			(filter_ratio 0.9)
			(enabled no)
			(allow_two_segments yes)
			(prefer_zone_connections no)
		)
		(net 1)
	)
	(via
		(at 135.95 105.1)
		(size 0.5)
		(drill 0.2)
		(layers "F.Cu" "B.Cu")
		(remove_unused_layers yes)
		(keep_end_layers yes)
		(free yes)
		(zone_layer_connections "In1.Cu" "In2.Cu")
		(teardrops
			(best_length_ratio 0.5)
			(max_length 1)
			(best_width_ratio 1)
			(max_width 2)
			(curved_edges yes)
			(filter_ratio 0.9)
			(enabled no)
			(allow_two_segments yes)
			(prefer_zone_connections yes)
		)
		(net 1)
	)
	(via
		(at 156.3 97.829343)
		(size 0.5)
		(drill 0.2)
		(layers "F.Cu" "B.Cu")
		(remove_unused_layers yes)
		(keep_end_layers yes)
		(free yes)
		(zone_layer_connections "In1.Cu" "In2.Cu")
		(teardrops
			(best_length_ratio 0.5)
			(max_length 1)
			(best_width_ratio 1)
			(max_width 2)
			(curved_edges yes)
			(filter_ratio 0.9)
			(enabled no)
			(allow_two_segments yes)
			(prefer_zone_connections yes)
		)
		(net 1)
	)
	(via
		(at 156.3 102.829343)
		(size 0.5)
		(drill 0.2)
		(layers "F.Cu" "B.Cu")
		(remove_unused_layers yes)
		(keep_end_layers yes)
		(free yes)
		(zone_layer_connections "In1.Cu" "In2.Cu")
		(teardrops
			(best_length_ratio 0.5)
			(max_length 1)
			(best_width_ratio 1)
			(max_width 2)
			(curved_edges yes)
			(filter_ratio 0.9)
			(enabled no)
			(allow_two_segments yes)
			(prefer_zone_connections yes)
		)
		(net 1)
	)
	(via
		(at 156.3 105.329343)
		(size 0.5)
		(drill 0.2)
		(layers "F.Cu" "B.Cu")
		(remove_unused_layers yes)
		(keep_end_layers yes)
		(free yes)
		(zone_layer_connections "In1.Cu" "In2.Cu")
		(teardrops
			(best_length_ratio 0.5)
			(max_length 1)
			(best_width_ratio 1)
			(max_width 2)
			(curved_edges yes)
			(filter_ratio 0.9)
			(enabled no)
			(allow_two_segments yes)
			(prefer_zone_connections yes)
		)
		(net 1)
	)
	(via
		(at 141.277041 93.392904)
		(size 0.5)
		(drill 0.2)
		(layers "F.Cu" "B.Cu")
		(remove_unused_layers yes)
		(keep_end_layers yes)
		(zone_layer_connections "In1.Cu" "In2.Cu")
		(teardrops
			(best_length_ratio 0.5)
			(max_length 1)
			(best_width_ratio 1)
			(max_width 2)
			(curved_edges yes)
			(filter_ratio 0.9)
			(enabled no)
			(allow_two_segments yes)
			(prefer_zone_connections no)
		)
		(net 1)
	)
	(via
		(at 147.405237 127.03)
		(size 0.5)
		(drill 0.2)
		(layers "F.Cu" "B.Cu")
		(remove_unused_layers yes)
		(keep_end_layers yes)
		(zone_layer_connections "In1.Cu" "In2.Cu")
		(teardrops
			(best_length_ratio 0.5)
			(max_length 1)
			(best_width_ratio 1)
			(max_width 2)
			(curved_edges yes)
			(filter_ratio 0.9)
			(enabled no)
			(allow_two_segments yes)
			(prefer_zone_connections yes)
		)
		(net 1)
	)
	(via
		(at 156.3 57.15)
		(size 0.5)
		(drill 0.2)
		(layers "F.Cu" "B.Cu")
		(remove_unused_layers yes)
		(keep_end_layers yes)
		(free yes)
		(zone_layer_connections "In1.Cu" "In2.Cu")
		(teardrops
			(best_length_ratio 0.5)
			(max_length 1)
			(best_width_ratio 1)
			(max_width 2)
			(curved_edges yes)
			(filter_ratio 0.9)
			(enabled no)
			(allow_two_segments yes)
			(prefer_zone_connections yes)
		)
		(net 1)
	)
	(segment
		(start 140.04 97.9)
		(end 139.45 97.9)
		(width 0.4)
		(layer "B.Cu")
		(net 1)
	)
	(segment
		(start 156.29 124.7)
		(end 155.724427 124.7)
		(width 0.4)
		(layer "B.Cu")
		(net 1)
	)
	(segment
		(start 150.89 95.57)
		(end 151.47 95.57)
		(width 0.4)
		(layer "B.Cu")
		(net 1)
	)
	(segment
		(start 155.724427 124.7)
		(end 155.654206 124.770221)
		(width 0.4)
		(layer "B.Cu")
		(net 1)
	)
	(segment
		(start 149.35 94.01475)
		(end 149.35 93.136169)
		(width 0.22)
		(layer "F.Cu")
		(net 2)
	)
	(segment
		(start 149.35204 93.094326)
		(end 149.169541 92.911827)
		(width 0.22)
		(layer "F.Cu")
		(net 2)
	)
	(segment
		(start 152.479 125.4165)
		(end 152.3025 125.24)
		(width 0.22)
		(layer "F.Cu")
		(net 2)
	)
	(segment
		(start 152.479 127.989345)
		(end 152.479 125.4165)
		(width 0.22)
		(layer "F.Cu")
		(net 2)
	)
	(via
		(at 149.169541 92.911827)
		(size 0.5)
		(drill 0.2)
		(layers "F.Cu" "B.Cu")
		(remove_unused_layers yes)
		(keep_end_layers yes)
		(zone_layer_connections)
		(teardrops
			(best_length_ratio 0.5)
			(max_length 1)
			(best_width_ratio 1)
			(max_width 2)
			(curved_edges yes)
			(filter_ratio 0.9)
			(enabled no)
			(allow_two_segments yes)
			(prefer_zone_connections yes)
		)
		(net 2)
	)
	(via
		(at 152.3025 125.24)
		(size 0.5)
		(drill 0.2)
		(layers "F.Cu" "B.Cu")
		(remove_unused_layers yes)
		(keep_end_layers yes)
		(zone_layer_connections)
		(teardrops
			(best_length_ratio 0.5)
			(max_length 1)
			(best_width_ratio 1)
			(max_width 2)
			(curved_edges yes)
			(filter_ratio 0.9)
			(enabled no)
			(allow_two_segments yes)
			(prefer_zone_connections yes)
		)
		(net 2)
	)
	(segment
		(start 152.485 119.235001)
		(end 152.485 125.0575)
		(width 0.22)
		(layer "B.Cu")
		(net 2)
	)
	(segment
		(start 149.847043 94.196249)
		(end 149.847061 98.13874)
		(width 0.22)
		(layer "B.Cu")
		(net 2)
	)
	(segment
		(start 149.35204 93.701259)
		(end 149.847043 94.196249)
		(width 0.22)
		(layer "B.Cu")
		(net 2)
	)
	(segment
		(start 151.384985 99.676715)
		(end 151.384993 118.135002)
		(width 0.22)
		(layer "B.Cu")
		(net 2)
	)
	(segment
		(start 151.384993 118.135002)
		(end 152.485 119.235001)
		(width 0.22)
		(layer "B.Cu")
		(net 2)
	)
	(segment
		(start 152.485 125.0575)
		(end 152.3025 125.24)
		(width 0.22)
		(layer "B.Cu")
		(net 2)
	)
	(segment
		(start 149.847061 98.13874)
		(end 151.384985 99.676715)
		(width 0.22)
		(layer "B.Cu")
		(net 2)
	)
	(segment
		(start 149.35204 93.094326)
		(end 149.35204 93.701259)
		(width 0.22)
		(layer "B.Cu")
		(net 2)
	)
	(segment
		(start 149.169541 92.911827)
		(end 149.35204 93.094326)
		(width 0.22)
		(layer "B.Cu")
		(net 2)
	)
	(segment
		(start 143.215 93.21)
		(end 143.242283 93.21)
		(width 0.22)
		(layer "F.Cu")
		(net 3)
	)
	(segment
		(start 143.359665 93.327382)
		(end 143.359666 93.890279)
		(width 0.22)
		(layer "F.Cu")
		(net 3)
	)
	(segment
		(start 146.477 128.009474)
		(end 146.477 125.120692)
		(width 0.22)
		(layer "F.Cu")
		(net 3)
	)
	(segment
		(start 146.477 125.120692)
		(end 146.347683 124.991375)
		(width 0.22)
		(layer "F.Cu")
		(net 3)
	)
	(segment
		(start 143.242283 93.21)
		(end 143.359665 93.327382)
		(width 0.22)
		(layer "F.Cu")
		(net 3)
	)
	(via
		(at 143.215 93.21)
		(size 0.5)
		(drill 0.2)
		(layers "F.Cu" "B.Cu")
		(remove_unused_layers yes)
		(keep_end_layers yes)
		(zone_layer_connections)
		(net 3)
	)
	(via
		(at 146.347683 124.991375)
		(size 0.5)
		(drill 0.2)
		(layers "F.Cu" "B.Cu")
		(remove_unused_layers yes)
		(keep_end_layers yes)
		(zone_layer_connections)
		(net 3)
	)
	(segment
		(start 143.354999 93.349999)
		(end 143.215 93.21)
		(width 0.22)
		(layer "B.Cu")
		(net 3)
	)
	(segment
		(start 143.354999 95.914831)
		(end 143.354999 93.349999)
		(width 0.22)
		(layer "B.Cu")
		(net 3)
	)
	(segment
		(start 144.285 118.478346)
		(end 144.285 96.844832)
		(width 0.22)
		(layer "B.Cu")
		(net 3)
	)
	(segment
		(start 144.285 96.844832)
		(end 143.354999 95.914831)
		(width 0.22)
		(layer "B.Cu")
		(net 3)
	)
	(segment
		(start 146.487682 120.681028)
		(end 144.285 118.478346)
		(width 0.22)
		(layer "B.Cu")
		(net 3)
	)
	(segment
		(start 146.487682 124.851376)
		(end 146.487682 120.681028)
		(width 0.22)
		(layer "B.Cu")
		(net 3)
	)
	(segment
		(start 146.347683 124.991375)
		(end 146.487682 124.851376)
		(width 0.22)
		(layer "B.Cu")
		(net 3)
	)
	(segment
		(start 150.98 119.923346)
		(end 150.98 127.988345)
		(width 0.22)
		(layer "F.Cu")
		(net 4)
	)
	(segment
		(start 148.35 117.293346)
		(end 150.98 119.923346)
		(width 0.22)
		(layer "F.Cu")
		(net 4)
	)
	(segment
		(start 148.35 96.75553)
		(end 148.35 117.293346)
		(width 0.22)
		(layer "F.Cu")
		(net 4)
	)
	(segment
		(start 147.7 95.18)
		(end 147.729305 95.18)
		(width 0.22)
		(layer "F.Cu")
		(net 5)
	)
	(segment
		(start 147.84 94.579988)
		(end 147.84 95.069305)
		(width 0.22)
		(layer "F.Cu")
		(net 5)
	)
	(segment
		(start 149.3025 123.36)
		(end 149.479 123.5365)
		(width 0.22)
		(layer "F.Cu")
		(net 5)
	)
	(segment
		(start 147.729305 95.18)
		(end 147.84 95.069305)
		(width 0.22)
		(layer "F.Cu")
		(net 5)
	)
	(segment
		(start 149.479 123.5365)
		(end 149.479 127.989345)
		(width 0.22)
		(layer "F.Cu")
		(net 5)
	)
	(via
		(at 147.7 95.18)
		(size 0.5)
		(drill 0.2)
		(layers "F.Cu" "B.Cu")
		(remove_unused_layers yes)
		(keep_end_layers yes)
		(zone_layer_connections)
		(net 5)
	)
	(via
		(at 149.3025 123.36)
		(size 0.5)
		(drill 0.2)
		(layers "F.Cu" "B.Cu")
		(remove_unused_layers yes)
		(keep_end_layers yes)
		(zone_layer_connections)
		(teardrops
			(best_length_ratio 0.5)
			(max_length 1)
			(best_width_ratio 1)
			(max_width 2)
			(curved_edges yes)
			(filter_ratio 0.9)
			(enabled no)
			(allow_two_segments yes)
			(prefer_zone_connections yes)
		)
		(net 5)
	)
	(segment
		(start 148.569387 96.820013)
		(end 148.569387 96.802733)
		(width 0.22)
		(layer "B.Cu")
		(net 5)
	)
	(segment
		(start 149.484001 122.44668)
		(end 149.484 122.446679)
		(width 0.22)
		(layer "B.Cu")
		(net 5)
	)
	(segment
		(start 147.839999 95.319999)
		(end 147.7 95.18)
		(width 0.22)
		(layer "B.Cu")
		(net 5)
	)
	(segment
		(start 148.611039 97.924146)
		(end 148.611039 96.861663)
		(width 0.22)
		(layer "B.Cu")
		(net 5)
	)
	(segment
		(start 149.484 123.1785)
		(end 149.484001 122.44668)
		(width 0.22)
		(layer "B.Cu")
		(net 5)
	)
	(segment
		(start 149.484 120.083987)
		(end 147.03355 117.633537)
		(width 0.22)
		(layer "B.Cu")
		(net 5)
	)
	(segment
		(start 148.611039 96.861663)
		(end 148.569387 96.820013)
		(width 0.22)
		(layer "B.Cu")
		(net 5)
	)
	(segment
		(start 147.03355 117.633537)
		(end 147.033542 99.501647)
		(width 0.22)
		(layer "B.Cu")
		(net 5)
	)
	(segment
		(start 149.3025 123.36)
		(end 149.484 123.1785)
		(width 0.22)
		(layer "B.Cu")
		(net 5)
	)
	(segment
		(start 149.484 122.446679)
		(end 149.484 120.083987)
		(width 0.22)
		(layer "B.Cu")
		(net 5)
	)
	(segment
		(start 148.569387 96.802733)
		(end 147.839999 96.073345)
		(width 0.22)
		(layer "B.Cu")
		(net 5)
	)
	(segment
		(start 147.033542 99.501647)
		(end 148.611039 97.924146)
		(width 0.22)
		(layer "B.Cu")
		(net 5)
	)
	(segment
		(start 147.839999 96.073345)
		(end 147.839999 95.319999)
		(width 0.22)
		(layer "B.Cu")
		(net 5)
	)
	(segment
		(start 150.18 96.75553)
		(end 150.18 100.096654)
		(width 0.22)
		(layer "F.Cu")
		(net 6)
	)
	(segment
		(start 153.12 103.036654)
		(end 153.12 124.07)
		(width 0.22)
		(layer "F.Cu")
		(net 6)
	)
	(segment
		(start 154.31 125.4275)
		(end 154.31 127.988345)
		(width 0.22)
		(layer "F.Cu")
		(net 6)
	)
	(segment
		(start 154.311 125.261)
		(end 154.311 125.4265)
		(width 0.22)
		(layer "F.Cu")
		(net 6)
	)
	(segment
		(start 153.12 124.07)
		(end 154.311 125.261)
		(width 0.22)
		(layer "F.Cu")
		(net 6)
	)
	(segment
		(start 154.311 125.4265)
		(end 154.31 125.4275)
		(width 0.22)
		(layer "F.Cu")
		(net 6)
	)
	(segment
		(start 150.18 100.096654)
		(end 153.12 103.036654)
		(width 0.22)
		(layer "F.Cu")
		(net 6)
	)
	(segment
		(start 142.68 117.896654)
		(end 145.615 120.831654)
		(width 0.22)
		(layer "F.Cu")
		(net 7)
	)
	(segment
		(start 145.615 123.389)
		(end 145.31 123.694)
		(width 0.22)
		(layer "F.Cu")
		(net 7)
	)
	(segment
		(start 145.615 120.831654)
		(end 145.615 123.389)
		(width 0.22)
		(layer "F.Cu")
		(net 7)
	)
	(segment
		(start 145.31 123.694)
		(end 145.31 127.989172)
		(width 0.22)
		(layer "F.Cu")
		(net 7)
	)
	(segment
		(start 142.68 96.76)
		(end 142.68 117.896654)
		(width 0.22)
		(layer "F.Cu")
		(net 7)
	)
	(segment
		(start 143.807049 93.21)
		(end 143.689667 93.327382)
		(width 0.22)
		(layer "F.Cu")
		(net 8)
	)
	(segment
		(start 143.825 93.21)
		(end 143.807049 93.21)
		(width 0.22)
		(layer "F.Cu")
		(net 8)
	)
	(segment
		(start 146.81 127.998474)
		(end 146.81 125.139058)
		(width 0.22)
		(layer "F.Cu")
		(net 8)
	)
	(segment
		(start 146.81 125.139058)
		(end 146.957683 124.991375)
		(width 0.22)
		(layer "F.Cu")
		(net 8)
	)
	(segment
		(start 143.689666 93.485517)
		(end 143.689666 93.905529)
		(width 0.22)
		(layer "F.Cu")
		(net 8)
	)
	(segment
		(start 143.689666 93.485517)
		(end 143.689667 93.327382)
		(width 0.22)
		(layer "F.Cu")
		(net 8)
	)
	(via
		(at 146.957683 124.991375)
		(size 0.5)
		(drill 0.2)
		(layers "F.Cu" "B.Cu")
		(remove_unused_layers yes)
		(keep_end_layers yes)
		(zone_layer_connections)
		(net 8)
	)
	(via
		(at 143.825 93.21)
		(size 0.5)
		(drill 0.2)
		(layers "F.Cu" "B.Cu")
		(remove_unused_layers yes)
		(keep_end_layers yes)
		(zone_layer_connections)
		(net 8)
	)
	(segment
		(start 143.685001 93.349999)
		(end 143.825 93.21)
		(width 0.22)
		(layer "B.Cu")
		(net 8)
	)
	(segment
		(start 144.616 118.342654)
		(end 144.616 96.707728)
		(width 0.22)
		(layer "B.Cu")
		(net 8)
	)
	(segment
		(start 144.616 96.707728)
		(end 143.685001 95.776729)
		(width 0.22)
		(layer "B.Cu")
		(net 8)
	)
	(segment
		(start 143.685001 95.776729)
		(end 143.685001 93.349999)
		(width 0.22)
		(layer "B.Cu")
		(net 8)
	)
	(segment
		(start 146.817684 120.544338)
		(end 144.616 118.342654)
		(width 0.22)
		(layer "B.Cu")
		(net 8)
	)
	(segment
		(start 146.957683 124.991375)
		(end 146.817684 124.851376)
		(width 0.22)
		(layer "B.Cu")
		(net 8)
	)
	(segment
		(start 146.817684 124.851376)
		(end 146.817684 120.544338)
		(width 0.22)
		(layer "B.Cu")
		(net 8)
	)
	(segment
		(start 152.79 103.173346)
		(end 152.79 124.21)
		(width 0.22)
		(layer "F.Cu")
		(net 9)
	)
	(segment
		(start 149.85 100.233346)
		(end 152.79 103.173346)
		(width 0.22)
		(layer "F.Cu")
		(net 9)
	)
	(segment
		(start 153.98 125.4)
		(end 153.98 127.99)
		(width 0.22)
		(layer "F.Cu")
		(net 9)
	)
	(segment
		(start 152.79 124.21)
		(end 153.98 125.4)
		(width 0.22)
		(layer "F.Cu")
		(net 9)
	)
	(segment
		(start 149.85 96.75553)
		(end 149.85 100.233346)
		(width 0.22)
		(layer "F.Cu")
		(net 9)
	)
	(segment
		(start 149.81 123.5475)
		(end 149.81 127.988345)
		(width 0.22)
		(layer "F.Cu")
		(net 10)
	)
	(segment
		(start 148.31 95.18)
		(end 148.171 95.041)
		(width 0.22)
		(layer "F.Cu")
		(net 10)
	)
	(segment
		(start 149.9975 123.36)
		(end 149.81 123.5475)
		(width 0.22)
		(layer "F.Cu")
		(net 10)
	)
	(segment
		(start 148.171 94.78)
		(end 148.171 94.58)
		(width 0.22)
		(layer "F.Cu")
		(net 10)
	)
	(segment
		(start 148.171 95.041)
		(end 148.171 94.78)
		(width 0.22)
		(layer "F.Cu")
		(net 10)
	)
	(via
		(at 148.31 95.18)
		(size 0.5)
		(drill 0.2)
		(layers "F.Cu" "B.Cu")
		(remove_unused_layers yes)
		(keep_end_layers yes)
		(zone_layer_connections)
		(net 10)
	)
	(via
		(at 149.9975 123.36)
		(size 0.5)
		(drill 0.2)
		(layers "F.Cu" "B.Cu")
		(remove_unused_layers yes)
		(keep_end_layers yes)
		(zone_layer_connections)
		(teardrops
			(best_length_ratio 0.5)
			(max_length 1)
			(best_width_ratio 1)
			(max_width 2)
			(curved_edges yes)
			(filter_ratio 0.9)
			(enabled no)
			(allow_two_segments yes)
			(prefer_zone_connections yes)
		)
		(net 10)
	)
	(segment
		(start 148.900384 96.667038)
		(end 148.170001 95.936655)
		(width 0.22)
		(layer "B.Cu")
		(net 10)
	)
	(segment
		(start 148.942039 98.06125)
		(end 148.942039 96.998762)
		(width 0.22)
		(layer "B.Cu")
		(net 10)
	)
	(segment
		(start 148.942039 96.998762)
		(end 148.942041 96.99876)
		(width 0.22)
		(layer "B.Cu")
		(net 10)
	)
	(segment
		(start 148.170001 95.936655)
		(end 148.170001 95.319999)
		(width 0.22)
		(layer "B.Cu")
		(net 10)
	)
	(segment
		(start 148.900384 96.682901)
		(end 148.900384 96.667038)
		(width 0.22)
		(layer "B.Cu")
		(net 10)
	)
	(segment
		(start 149.9975 123.36)
		(end 149.815001 123.177501)
		(width 0.22)
		(layer "B.Cu")
		(net 10)
	)
	(segment
		(start 149.643856 119.775736)
		(end 147.36455 117.496432)
		(width 0.22)
		(layer "B.Cu")
		(net 10)
	)
	(segment
		(start 148.942041 96.99876)
		(end 148.942039 96.724557)
		(width 0.22)
		(layer "B.Cu")
		(net 10)
	)
	(segment
		(start 149.815001 123.177501)
		(end 149.815001 119.946877)
		(width 0.22)
		(layer "B.Cu")
		(net 10)
	)
	(segment
		(start 148.170001 95.319999)
		(end 148.31 95.18)
		(width 0.22)
		(layer "B.Cu")
		(net 10)
	)
	(segment
		(start 149.815001 119.946877)
		(end 149.64386 119.775736)
		(width 0.22)
		(layer "B.Cu")
		(net 10)
	)
	(segment
		(start 147.364543 99.638751)
		(end 148.942039 98.06125)
		(width 0.22)
		(layer "B.Cu")
		(net 10)
	)
	(segment
		(start 148.942037 96.724552)
		(end 148.900384 96.682901)
		(width 0.22)
		(layer "B.Cu")
		(net 10)
	)
	(segment
		(start 148.942039 96.724557)
		(end 148.942037 96.724552)
		(width 0.22)
		(layer "B.Cu")
		(net 10)
	)
	(segment
		(start 149.64386 119.775736)
		(end 149.643856 119.775736)
		(width 0.22)
		(layer "B.Cu")
		(net 10)
	)
	(segment
		(start 147.36455 117.496432)
		(end 147.364543 99.638751)
		(width 0.22)
		(layer "B.Cu")
		(net 10)
	)
	(segment
		(start 147.182042 96.975845)
		(end 147.322041 97.115844)
		(width 0.22)
		(layer "F.Cu")
		(net 12)
	)
	(segment
		(start 147.182042 96.557903)
		(end 147.182042 96.975845)
		(width 0.22)
		(layer "F.Cu")
		(net 12)
	)
	(segment
		(start 147.267041 96.472904)
		(end 147.182042 96.557903)
		(width 0.22)
		(layer "F.Cu")
		(net 12)
	)
	(via
		(at 147.322041 97.115844)
		(size 0.5)
		(drill 0.2)
		(layers "F.Cu" "B.Cu")
		(remove_unused_layers yes)
		(keep_end_layers yes)
		(zone_layer_connections)
		(net 12)
	)
	(segment
		(start 146.45 95.957589)
		(end 146.45 95.39)
		(width 0.22)
		(layer "B.Cu")
		(net 12)
	)
	(segment
		(start 146.859128 96.185782)
		(end 146.678193 96.185782)
		(width 0.22)
		(layer "B.Cu")
		(net 12)
	)
	(segment
		(start 147.183041 96.976844)
		(end 147.183041 96.920749)
		(width 0.22)
		(layer "B.Cu")
		(net 12)
	)
	(segment
		(start 146.678193 96.185782)
		(end 146.45 95.957589)
		(width 0.22)
		(layer "B.Cu")
		(net 12)
	)
	(segment
		(start 147.182042 96.508696)
		(end 146.859128 96.185782)
		(width 0.22)
		(layer "B.Cu")
		(net 12)
	)
	(segment
		(start 147.183041 96.920749)
		(end 147.182042 96.91975)
		(width 0.22)
		(layer "B.Cu")
		(net 12)
	)
	(segment
		(start 147.322041 97.115844)
		(end 147.183041 96.976844)
		(width 0.22)
		(layer "B.Cu")
		(net 12)
	)
	(segment
		(start 147.182042 96.91975)
		(end 147.182042 96.508696)
		(width 0.22)
		(layer "B.Cu")
		(net 12)
	)
	(segment
		(start 146.767041 96.472904)
		(end 146.85204 96.557903)
		(width 0.22)
		(layer "F.Cu")
		(net 13)
	)
	(segment
		(start 146.85204 96.975845)
		(end 146.712041 97.115844)
		(width 0.22)
		(layer "F.Cu")
		(net 13)
	)
	(segment
		(start 146.85204 96.557903)
		(end 146.85204 96.975845)
		(width 0.22)
		(layer "F.Cu")
		(net 13)
	)
	(via
		(at 146.712041 97.115844)
		(size 0.5)
		(drill 0.2)
		(layers "F.Cu" "B.Cu")
		(remove_unused_layers yes)
		(keep_end_layers yes)
		(zone_layer_connections)
		(net 13)
	)
	(segment
		(start 146.722024 96.516782)
		(end 146.541089 96.516782)
		(width 0.22)
		(layer "B.Cu")
		(net 13)
	)
	(segment
		(start 146.712041 97.115844)
		(end 146.851041 96.976844)
		(width 0.22)
		(layer "B.Cu")
		(net 13)
	)
	(segment
		(start 146.541089 96.516782)
		(end 146.119 96.094693)
		(width 0.22)
		(layer "B.Cu")
		(net 13)
	)
	(segment
		(start 146.119 96.094693)
		(end 146.119 95.392896)
		(width 0.22)
		(layer "B.Cu")
		(net 13)
	)
	(segment
		(start 146.851042 96.6458)
		(end 146.722024 96.516782)
		(width 0.22)
		(layer "B.Cu")
		(net 13)
	)
	(segment
		(start 146.851041 96.976844)
		(end 146.851042 96.6458)
		(width 0.22)
		(layer "B.Cu")
		(net 13)
	)
	(segment
		(start 151.31 119.786654)
		(end 151.31 127.988345)
		(width 0.22)
		(layer "F.Cu")
		(net 14)
	)
	(segment
		(start 148.68 117.156654)
		(end 151.31 119.786654)
		(width 0.22)
		(layer "F.Cu")
		(net 14)
	)
	(segment
		(start 148.68 96.75553)
		(end 148.68 117.156654)
		(width 0.22)
		(layer "F.Cu")
		(net 14)
	)
	(segment
		(start 142.17 94.49)
		(end 142.17 94.91)
		(width 0.22)
		(layer "F.Cu")
		(net 15)
	)
	(segment
		(start 142.344593 95.084593)
		(end 142.17 94.91)
		(width 0.22)
		(layer "F.Cu")
		(net 15)
	)
	(segment
		(start 143.81 127.99)
		(end 143.81 122.89)
		(width 0.22)
		(layer "F.Cu")
		(net 15)
	)
	(segment
		(start 142.364541 95.084593)
		(end 142.344593 95.084593)
		(width 0.22)
		(layer "F.Cu")
		(net 15)
	)
	(segment
		(start 143.81 122.89)
		(end 144 122.7)
		(width 0.22)
		(layer "F.Cu")
		(net 15)
	)
	(via
		(at 144 122.7)
		(size 0.5)
		(drill 0.2)
		(layers "F.Cu" "B.Cu")
		(remove_unused_layers yes)
		(keep_end_layers yes)
		(zone_layer_connections)
		(teardrops
			(best_length_ratio 0.5)
			(max_length 1)
			(best_width_ratio 1)
			(max_width 2)
			(curved_edges yes)
			(filter_ratio 0.9)
			(enabled no)
			(allow_two_segments yes)
			(prefer_zone_connections yes)
		)
		(net 15)
	)
	(via
		(at 142.364541 95.084593)
		(size 0.5)
		(drill 0.2)
		(layers "F.Cu" "B.Cu")
		(remove_unused_layers yes)
		(keep_end_layers yes)
		(zone_layer_connections)
		(teardrops
			(best_length_ratio 0.5)
			(max_length 1)
			(best_width_ratio 1)
			(max_width 2)
			(curved_edges yes)
			(filter_ratio 0.9)
			(enabled no)
			(allow_two_segments yes)
			(prefer_zone_connections yes)
		)
		(net 15)
	)
	(segment
		(start 141.281547 98.971799)
		(end 141.281529 118.245357)
		(width 0.22)
		(layer "B.Cu")
		(net 15)
	)
	(segment
		(start 143.8195 120.783327)
		(end 143.8195 122.5195)
		(width 0.22)
		(layer "B.Cu")
		(net 15)
	)
	(segment
		(start 142.685 96.591654)
		(end 142.685 97.568346)
		(width 0.22)
		(layer "B.Cu")
		(net 15)
	)
	(segment
		(start 142.182041 96.088695)
		(end 142.685 96.591654)
		(width 0.22)
		(layer "B.Cu")
		(net 15)
	)
	(segment
		(start 141.281529 118.245357)
		(end 143.8195 120.783327)
		(width 0.22)
		(layer "B.Cu")
		(net 15)
	)
	(segment
		(start 142.182041 95.267093)
		(end 142.182041 96.088695)
		(width 0.22)
		(layer "B.Cu")
		(net 15)
	)
	(segment
		(start 143.8195 122.5195)
		(end 144 122.7)
		(width 0.22)
		(layer "B.Cu")
		(net 15)
	)
	(segment
		(start 142.364541 95.084593)
		(end 142.182041 95.267093)
		(width 0.22)
		(layer "B.Cu")
		(net 15)
	)
	(segment
		(start 142.685 97.568346)
		(end 141.281547 98.971799)
		(width 0.22)
		(layer "B.Cu")
		(net 15)
	)
	(segment
		(start 148.3445 125.348552)
		(end 148.3445 125.821448)
		(width 0.22)
		(layer "F.Cu")
		(net 16)
	)
	(segment
		(start 148.0445 125.048553)
		(end 148.047474 125.051526)
		(width 0.22)
		(layer "F.Cu")
		(net 16)
	)
	(segment
		(start 148.0445 125.0545)
		(end 148.050448 125.0545)
		(width 0.22)
		(layer "F.Cu")
		(net 16)
	)
	(segment
		(start 143.84 98.293347)
		(end 145.415 99.868346)
		(width 0.22)
		(layer "F.Cu")
		(net 16)
	)
	(segment
		(start 147.899 120.422346)
		(end 147.899 124.897105)
		(width 0.22)
		(layer "F.Cu")
		(net 16)
	)
	(segment
		(start 148.047474 125.051526)
		(end 148.0445 125.0545)
		(width 0.22)
		(layer "F.Cu")
		(net 16)
	)
	(segment
		(start 145.415 117.938347)
		(end 147.899 120.422346)
		(width 0.22)
		(layer "F.Cu")
		(net 16)
	)
	(segment
		(start 147.899 124.897105)
		(end 148.0445 125.042604)
		(width 0.22)
		(layer "F.Cu")
		(net 16)
	)
	(segment
		(start 148.0445 125.042604)
		(end 148.0445 125.048553)
		(width 0.22)
		(layer "F.Cu")
		(net 16)
	)
	(segment
		(start 148.3445 125.821448)
		(end 147.977 126.188948)
		(width 0.22)
		(layer "F.Cu")
		(net 16)
	)
	(segment
		(start 143.84 96.759988)
		(end 143.84 98.293347)
		(width 0.22)
		(layer "F.Cu")
		(net 16)
	)
	(segment
		(start 145.415 99.868346)
		(end 145.415 117.938347)
		(width 0.22)
		(layer "F.Cu")
		(net 16)
	)
	(segment
		(start 148.050448 125.0545)
		(end 148.3445 125.348552)
		(width 0.22)
		(layer "F.Cu")
		(net 16)
	)
	(segment
		(start 147.977 126.188948)
		(end 147.977 128.012)
		(width 0.22)
		(layer "F.Cu")
		(net 16)
	)
	(segment
		(start 140.05 91.177152)
		(end 140.055145 91.172007)
		(width 0.4)
		(layer "F.Cu")
		(net 17)
	)
	(segment
		(start 140.055145 91.172007)
		(end 140.055145 92.975145)
		(width 0.4)
		(layer "F.Cu")
		(net 17)
	)
	(segment
		(start 140.055145 92.975145)
		(end 140.06 92.98)
		(width 0.4)
		(layer "F.Cu")
		(net 17)
	)
	(via
		(at 140.06 93.57)
		(size 0.5)
		(drill 0.2)
		(layers "F.Cu" "B.Cu")
		(remove_unused_layers yes)
		(keep_end_layers yes)
		(zone_layer_connections)
		(teardrops
			(best_length_ratio 0.5)
			(max_length 1)
			(best_width_ratio 1)
			(max_width 2)
			(curved_edges yes)
			(filter_ratio 0.9)
			(enabled no)
			(allow_two_segments yes)
			(prefer_zone_connections yes)
		)
		(net 17)
	)
	(via
		(at 140.25 96.35)
		(size 0.5)
		(drill 0.2)
		(layers "F.Cu" "B.Cu")
		(remove_unused_layers yes)
		(keep_end_layers yes)
		(zone_layer_connections)
		(teardrops
			(best_length_ratio 0.5)
			(max_length 1)
			(best_width_ratio 1)
			(max_width 2)
			(curved_edges yes)
			(filter_ratio 0.9)
			(enabled no)
			(allow_two_segments yes)
			(prefer_zone_connections yes)
		)
		(net 17)
	)
	(via
		(at 139.7 96.35)
		(size 0.5)
		(drill 0.2)
		(layers "F.Cu" "B.Cu")
		(remove_unused_layers yes)
		(keep_end_layers yes)
		(zone_layer_connections)
		(teardrops
			(best_length_ratio 0.5)
			(max_length 1)
			(best_width_ratio 1)
			(max_width 2)
			(curved_edges yes)
			(filter_ratio 0.9)
			(enabled no)
			(allow_two_segments yes)
			(prefer_zone_connections yes)
		)
		(net 17)
	)
	(via
		(at 140.05 90.61)
		(size 0.5)
		(drill 0.2)
		(layers "F.Cu" "B.Cu")
		(remove_unused_layers yes)
		(keep_end_layers yes)
		(zone_layer_connections)
		(teardrops
			(best_length_ratio 0.5)
			(max_length 1)
			(best_width_ratio 1)
			(max_width 2)
			(curved_edges yes)
			(filter_ratio 0.9)
			(enabled no)
			(allow_two_segments yes)
			(prefer_zone_connections yes)
		)
		(net 17)
	)
	(via
		(at 140.06 92.98)
		(size 0.5)
		(drill 0.2)
		(layers "F.Cu" "B.Cu")
		(remove_unused_layers yes)
		(keep_end_layers yes)
		(zone_layer_connections)
		(teardrops
			(best_length_ratio 0.5)
			(max_length 1)
			(best_width_ratio 1)
			(max_width 2)
			(curved_edges yes)
			(filter_ratio 0.9)
			(enabled no)
			(allow_two_segments yes)
			(prefer_zone_connections yes)
		)
		(net 17)
	)
	(via
		(at 140.05 91.22)
		(size 0.5)
		(drill 0.2)
		(layers "F.Cu" "B.Cu")
		(remove_unused_layers yes)
		(keep_end_layers yes)
		(zone_layer_connections)
		(teardrops
			(best_length_ratio 0.5)
			(max_length 1)
			(best_width_ratio 1)
			(max_width 2)
			(curved_edges yes)
			(filter_ratio 0.9)
			(enabled no)
			(allow_two_segments yes)
			(prefer_zone_connections yes)
		)
		(net 17)
	)
	(segment
		(start 148.81 83.61)
		(end 151.35 86.15)
		(width 0.4)
		(layer "B.Cu")
		(net 17)
	)
	(segment
		(start 139.7 93.93)
		(end 140.06 93.57)
		(width 0.4)
		(layer "B.Cu")
		(net 17)
	)
	(segment
		(start 140.05 86.2)
		(end 142.64 83.61)
		(width 0.4)
		(layer "B.Cu")
		(net 17)
	)
	(segment
		(start 142.64 83.61)
		(end 148.81 83.61)
		(width 0.4)
		(layer "B.Cu")
		(net 17)
	)
	(segment
		(start 139.45 96.94)
		(end 139.45 96.6)
		(width 0.4)
		(layer "B.Cu")
		(net 17)
	)
	(segment
		(start 151.35 86.15)
		(end 151.35 90.1)
		(width 0.4)
		(layer "B.Cu")
		(net 17)
	)
	(segment
		(start 140.25 95.75)
		(end 139.7 95.75)
		(width 0.4)
		(layer "B.Cu")
		(net 17)
	)
	(segment
		(start 140.25 96.35)
		(end 140.25 95.75)
		(width 0.4)
		(layer "B.Cu")
		(net 17)
	)
	(segment
		(start 139.45 96.6)
		(end 139.7 96.35)
		(width 0.4)
		(layer "B.Cu")
		(net 17)
	)
	(segment
		(start 139.7 96.35)
		(end 139.7 93.93)
		(width 0.4)
		(layer "B.Cu")
		(net 17)
	)
	(segment
		(start 140.055145 90.582007)
		(end 140.055145 86.205145)
		(width 0.4)
		(layer "B.Cu")
		(net 17)
	)
	(segment
		(start 140.055145 86.205145)
		(end 140.05 86.2)
		(width 0.4)
		(layer "B.Cu")
		(net 17)
	)
	(segment
		(start 152.81 127.988345)
		(end 152.81 125.4275)
		(width 0.22)
		(layer "F.Cu")
		(net 21)
	)
	(segment
		(start 152.81 125.4275)
		(end 152.9975 125.24)
		(width 0.22)
		(layer "F.Cu")
		(net 21)
	)
	(segment
		(start 149.682042 93.094326)
		(end 149.864541 92.911827)
		(width 0.22)
		(layer "F.Cu")
		(net 21)
	)
	(segment
		(start 149.68 94.03)
		(end 149.68 93.136169)
		(width 0.22)
		(layer "F.Cu")
		(net 21)
	)
	(via
		(at 149.864541 92.911827)
		(size 0.5)
		(drill 0.2)
		(layers "F.Cu" "B.Cu")
		(remove_unused_layers yes)
		(keep_end_layers yes)
		(zone_layer_connections)
		(teardrops
			(best_length_ratio 0.5)
			(max_length 1)
			(best_width_ratio 1)
			(max_width 2)
			(curved_edges yes)
			(filter_ratio 0.9)
			(enabled no)
			(allow_two_segments yes)
			(prefer_zone_connections yes)
		)
		(net 21)
	)
	(via
		(at 152.9975 125.24)
		(size 0.5)
		(drill 0.2)
		(layers "F.Cu" "B.Cu")
		(remove_unused_layers yes)
		(keep_end_layers yes)
		(zone_layer_connections)
		(teardrops
			(best_length_ratio 0.5)
			(max_length 1)
			(best_width_ratio 1)
			(max_width 2)
			(curved_edges yes)
			(filter_ratio 0.9)
			(enabled no)
			(allow_two_segments yes)
			(prefer_zone_connections yes)
		)
		(net 21)
	)
	(segment
		(start 149.864541 92.911827)
		(end 149.682042 93.094326)
		(width 0.22)
		(layer "B.Cu")
		(net 21)
	)
	(segment
		(start 150.177023 98.002064)
		(end 151.714982 99.540024)
		(width 0.22)
		(layer "B.Cu")
		(net 21)
	)
	(segment
		(start 152.815 125.0575)
		(end 152.9975 125.24)
		(width 0.22)
		(layer "B.Cu")
		(net 21)
	)
	(segment
		(start 150.17704 94.059558)
		(end 150.177023 98.002064)
		(width 0.22)
		(layer "B.Cu")
		(net 21)
	)
	(segment
		(start 151.714982 99.540024)
		(end 151.714996 117.998308)
		(width 0.22)
		(layer "B.Cu")
		(net 21)
	)
	(segment
		(start 152.815 119.098312)
		(end 152.815 125.0575)
		(width 0.22)
		(layer "B.Cu")
		(net 21)
	)
	(segment
		(start 149.682042 93.564537)
		(end 150.17704 94.059558)
		(width 0.22)
		(layer "B.Cu")
		(net 21)
	)
	(segment
		(start 149.682042 93.094326)
		(end 149.682042 93.564537)
		(width 0.22)
		(layer "B.Cu")
		(net 21)
	)
	(segment
		(start 151.714996 117.998308)
		(end 152.815 119.098312)
		(width 0.22)
		(layer "B.Cu")
		(net 21)
	)
	(segment
		(start 146.080864 93.550416)
		(end 146.080864 92.980864)
		(width 0.2)
		(layer "F.Cu")
		(net 23)
	)
	(segment
		(start 146.12912 93.51)
		(end 146.144857 93.51)
		(width 0.22)
		(layer "F.Cu")
		(net 23)
	)
	(segment
		(start 146.27 93.635143)
		(end 146.27 94.27)
		(width 0.2)
		(layer "F.Cu")
		(net 23)
	)
	(segment
		(start 146.117341 93.586893)
		(end 146.117341 93.521779)
		(width 0.22)
		(layer "F.Cu")
		(net 23)
	)
	(segment
		(start 146.144857 93.51)
		(end 146.27 93.635143)
		(width 0.2)
		(layer "F.Cu")
		(net 23)
	)
	(segment
		(start 146.117341 93.521779)
		(end 146.13 93.50912)
		(width 0.2)
		(layer "F.Cu")
		(net 23)
	)
	(segment
		(start 146.117341 93.521779)
		(end 146.12912 93.51)
		(width 0.22)
		(layer "F.Cu")
		(net 23)
	)
	(segment
		(start 146.080864 92.980864)
		(end 146.08 92.98)
		(width 0.2)
		(layer "F.Cu")
		(net 23)
	)
	(segment
		(start 146.117341 93.586893)
		(end 146.080864 93.550416)
		(width 0.2)
		(layer "F.Cu")
		(net 23)
	)
	(via
		(at 146.117341 93.586893)
		(size 0.5)
		(drill 0.2)
		(layers "F.Cu" "B.Cu")
		(remove_unused_layers yes)
		(keep_end_layers yes)
		(zone_layer_connections)
		(net 23)
	)
	(segment
		(start 146.105098 93.599136)
		(end 146.080864 93.599136)
		(width 0.22)
		(layer "B.Cu")
		(net 23)
	)
	(segment
		(start 146.080864 93.599136)
		(end 145.93 93.75)
		(width 0.22)
		(layer "B.Cu")
		(net 23)
	)
	(segment
		(start 145.93 93.75)
		(end 145.93 94.06)
		(width 0.22)
		(layer "B.Cu")
		(net 23)
	)
	(segment
		(start 146.117341 93.586893)
		(end 146.105098 93.599136)
		(width 0.22)
		(layer "B.Cu")
		(net 23)
	)
	(segment
		(start 145.70541 97.737935)
		(end 145.732065 97.737935)
		(width 0.2)
		(layer "F.Cu")
		(net 24)
	)
	(segment
		(start 141.59 91.81)
		(end 141.59 90.73)
		(width 0.2)
		(layer "F.Cu")
		(net 24)
	)
	(segment
		(start 141.14 89.76)
		(end 141.04 89.66)
		(width 0.2)
		(layer "F.Cu")
		(net 24)
	)
	(segment
		(start 143.794966 92.476)
		(end 143.608966 92.29)
		(width 0.2)
		(layer "F.Cu")
		(net 24)
	)
	(segment
		(start 144.230001 92.750001)
		(end 143.956 92.476)
		(width 0.2)
		(layer "F.Cu")
		(net 24)
	)
	(segment
		(start 143.608966 92.29)
		(end 142.07 92.29)
		(width 0.2)
		(layer "F.Cu")
		(net 24)
	)
	(segment
		(start 142.07 92.29)
		(end 141.59 91.81)
		(width 0.2)
		(layer "F.Cu")
		(net 24)
	)
	(segment
		(start 145.732065 97.737935)
		(end 145.74 97.73)
		(width 0.2)
		(layer "F.Cu")
		(net 24)
	)
	(segment
		(start 141.14 90.28)
		(end 141.14 89.76)
		(width 0.2)
		(layer "F.Cu")
		(net 24)
	)
	(segment
		(start 143.956 92.476)
		(end 143.794966 92.476)
		(width 0.2)
		(layer "F.Cu")
		(net 24)
	)
	(segment
		(start 145.74 97.73)
		(end 145.74 96.505863)
		(width 0.2)
		(layer "F.Cu")
		(net 24)
	)
	(segment
		(start 141.59 90.73)
		(end 141.14 90.28)
		(width 0.2)
		(layer "F.Cu")
		(net 24)
	)
	(segment
		(start 144.243881 92.736999)
		(end 144.230879 92.750001)
		(width 0.2)
		(layer "F.Cu")
		(net 24)
	)
	(segment
		(start 144.230879 92.750001)
		(end 144.230001 92.750001)
		(width 0.2)
		(layer "F.Cu")
		(net 24)
	)
	(segment
		(start 141.04 89.66)
		(end 140.58 89.66)
		(width 0.2)
		(layer "F.Cu")
		(net 24)
	)
	(via
		(at 145.70541 97.737935)
		(size 0.5)
		(drill 0.2)
		(layers "F.Cu" "B.Cu")
		(remove_unused_layers yes)
		(keep_end_layers yes)
		(zone_layer_connections)
		(teardrops
			(best_length_ratio 0.5)
			(max_length 1)
			(best_width_ratio 1)
			(max_width 2)
			(curved_edges yes)
			(filter_ratio 0.9)
			(enabled no)
			(allow_two_segments yes)
			(prefer_zone_connections yes)
		)
		(net 24)
	)
	(via
		(at 144.243881 92.736999)
		(size 0.5)
		(drill 0.2)
		(layers "F.Cu" "B.Cu")
		(remove_unused_layers yes)
		(keep_end_layers yes)
		(zone_layer_connections)
		(net 24)
	)
	(segment
		(start 144.248114 92.951795)
		(end 144.747 93.450681)
		(width 0.2)
		(layer "B.Cu")
		(net 24)
	)
	(segment
		(start 144.301 92.802887)
		(end 144.243881 92.745768)
		(width 0.2)
		(layer "B.Cu")
		(net 24)
	)
	(segment
		(start 144.243881 92.736999)
		(end 144.248114 92.741232)
		(width 0.2)
		(layer "B.Cu")
		(net 24)
	)
	(segment
		(start 144.71 94.44)
		(end 144.71 95.71)
		(width 0.2)
		(layer "B.Cu")
		(net 24)
	)
	(segment
		(start 145.74 97.73)
		(end 145.732065 97.737935)
		(width 0.2)
		(layer "B.Cu")
		(net 24)
	)
	(segment
		(start 144.22 94.43)
		(end 144.7 94.43)
		(width 0.2)
		(layer "B.Cu")
		(net 24)
	)
	(segment
		(start 144.71 95.71)
		(end 145.74 96.74)
		(width 0.2)
		(layer "B.Cu")
		(net 24)
	)
	(segment
		(start 144.248114 92.741232)
		(end 144.248114 92.951795)
		(width 0.2)
		(layer "B.Cu")
		(net 24)
	)
	(segment
		(start 144.243881 92.745768)
		(end 144.243881 92.736999)
		(width 0.2)
		(layer "B.Cu")
		(net 24)
	)
	(segment
		(start 145.732065 97.737935)
		(end 145.70541 97.737935)
		(width 0.2)
		(layer "B.Cu")
		(net 24)
	)
	(segment
		(start 144.747 94.403)
		(end 144.71 94.44)
		(width 0.2)
		(layer "B.Cu")
		(net 24)
	)
	(segment
		(start 144.7 94.43)
		(end 144.71 94.44)
		(width 0.2)
		(layer "B.Cu")
		(net 24)
	)
	(segment
		(start 145.74 96.74)
		(end 145.74 97.73)
		(width 0.2)
		(layer "B.Cu")
		(net 24)
	)
	(segment
		(start 144.747 93.450681)
		(end 144.747 94.403)
		(width 0.2)
		(layer "B.Cu")
		(net 24)
	)
	(segment
		(start 143.479 127.991)
		(end 143.479 122.874)
		(width 0.22)
		(layer "F.Cu")
		(net 25)
	)
	(segment
		(start 143.479 122.874)
		(end 143.305 122.7)
		(width 0.22)
		(layer "F.Cu")
		(net 25)
	)
	(segment
		(start 141.84 94.49)
		(end 141.84 94.91)
		(width 0.22)
		(layer "F.Cu")
		(net 25)
	)
	(segment
		(start 141.669541 95.080459)
		(end 141.84 94.91)
		(width 0.22)
		(layer "F.Cu")
		(net 25)
	)
	(segment
		(start 141.669541 95.084593)
		(end 141.669541 95.080459)
		(width 0.22)
		(layer "F.Cu")
		(net 25)
	)
	(via
		(at 143.305 122.7)
		(size 0.5)
		(drill 0.2)
		(layers "F.Cu" "B.Cu")
		(remove_unused_layers yes)
		(keep_end_layers yes)
		(zone_layer_connections)
		(teardrops
			(best_length_ratio 0.5)
			(max_length 1)
			(best_width_ratio 1)
			(max_width 2)
			(curved_edges yes)
			(filter_ratio 0.9)
			(enabled no)
			(allow_two_segments yes)
			(prefer_zone_connections yes)
		)
		(net 25)
	)
	(via
		(at 141.669541 95.084593)
		(size 0.5)
		(drill 0.2)
		(layers "F.Cu" "B.Cu")
		(remove_unused_layers yes)
		(keep_end_layers yes)
		(zone_layer_connections)
		(teardrops
			(best_length_ratio 0.5)
			(max_length 1)
			(best_width_ratio 1)
			(max_width 2)
			(curved_edges yes)
			(filter_ratio 0.9)
			(enabled no)
			(allow_two_segments yes)
			(prefer_zone_connections yes)
		)
		(net 25)
	)
	(segment
		(start 142.355 97.431654)
		(end 140.949594 98.83706)
		(width 0.22)
		(layer "B.Cu")
		(net 25)
	)
	(segment
		(start 140.949594 98.83706)
		(end 140.949547 98.83706)
		(width 0.22)
		(layer "B.Cu")
		(net 25)
	)
	(segment
		(start 140.949547 98.83706)
		(end 140.949529 118.382875)
		(width 0.22)
		(layer "B.Cu")
		(net 25)
	)
	(segment
		(start 142.355 96.728346)
		(end 142.355 97.431654)
		(width 0.22)
		(layer "B.Cu")
		(net 25)
	)
	(segment
		(start 141.852041 95.267093)
		(end 141.852041 96.225387)
		(width 0.22)
		(layer "B.Cu")
		(net 25)
	)
	(segment
		(start 141.852041 96.225387)
		(end 142.355 96.728346)
		(width 0.22)
		(layer "B.Cu")
		(net 25)
	)
	(segment
		(start 140.949529 118.382875)
		(end 143.4875 120.920846)
		(width 0.22)
		(layer "B.Cu")
		(net 25)
	)
	(segment
		(start 141.669541 95.084593)
		(end 141.852041 95.267093)
		(width 0.22)
		(layer "B.Cu")
		(net 25)
	)
	(segment
		(start 143.4875 120.920846)
		(end 143.4875 122.5175)
		(width 0.22)
		(layer "B.Cu")
		(net 25)
	)
	(segment
		(start 143.4875 122.5175)
		(end 143.305 122.7)
		(width 0.22)
		(layer "B.Cu")
		(net 25)
	)
	(segment
		(start 142.35 118.034758)
		(end 145.284 120.968758)
		(width 0.22)
		(layer "F.Cu")
		(net 26)
	)
	(segment
		(start 145.284 123.251896)
		(end 144.979 123.556896)
		(width 0.22)
		(layer "F.Cu")
		(net 26)
	)
	(segment
		(start 144.979 123.556896)
		(end 144.979 127.990172)
		(width 0.22)
		(layer "F.Cu")
		(net 26)
	)
	(segment
		(start 142.35 96.76)
		(end 142.35 118.034758)
		(width 0.22)
		(layer "F.Cu")
		(net 26)
	)
	(segment
		(start 145.284 120.968758)
		(end 145.284 123.251896)
		(width 0.22)
		(layer "F.Cu")
		(net 26)
	)
	(segment
		(start 148.3755 124.911448)
		(end 148.6755 125.211448)
		(width 0.22)
		(layer "F.Cu")
		(net 27)
	)
	(segment
		(start 148.6755 125.958552)
		(end 148.31 126.324052)
		(width 0.22)
		(layer "F.Cu")
		(net 27)
	)
	(segment
		(start 148.23 124.76)
		(end 148.3755 124.9055)
		(width 0.22)
		(layer "F.Cu")
		(net 27)
	)
	(segment
		(start 144.17 96.759988)
		(end 144.17 98.155242)
		(width 0.22)
		(layer "F.Cu")
		(net 27)
	)
	(segment
		(start 144.17 98.155242)
		(end 145.746 99.731242)
		(width 0.22)
		(layer "F.Cu")
		(net 27)
	)
	(segment
		(start 148.6755 125.211448)
		(end 148.6755 125.958552)
		(width 0.22)
		(layer "F.Cu")
		(net 27)
	)
	(segment
		(start 145.746 99.731242)
		(end 145.746 117.801242)
		(width 0.22)
		(layer "F.Cu")
		(net 27)
	)
	(segment
		(start 145.746 117.801242)
		(end 148.23 120.285242)
		(width 0.22)
		(layer "F.Cu")
		(net 27)
	)
	(segment
		(start 148.23 120.285242)
		(end 148.23 124.76)
		(width 0.22)
		(layer "F.Cu")
		(net 27)
	)
	(segment
		(start 148.3755 124.9055)
		(end 148.3755 124.911448)
		(width 0.22)
		(layer "F.Cu")
		(net 27)
	)
	(segment
		(start 148.31 126.324052)
		(end 148.31 128.001)
		(width 0.22)
		(layer "F.Cu")
		(net 27)
	)
	(segment
		(start 137.527501 115.692499)
		(end 137.71 115.51)
		(width 0.22)
		(layer "F.Cu")
		(net 36)
	)
	(segment
		(start 141.990001 125.736655)
		(end 141.990001 120.705242)
		(width 0.22)
		(layer "F.Cu")
		(net 36)
	)
	(segment
		(start 137.718758 119.334)
		(end 137.516 119.131242)
		(width 0.22)
		(layer "F.Cu")
		(net 36)
	)
	(segment
		(start 141.990001 120.705242)
		(end 140.618758 119.334)
		(width 0.22)
		(layer "F.Cu")
		(net 36)
	)
	(segment
		(start 137.516 119.131242)
		(end 137.516 115.692499)
		(width 0.22)
		(layer "F.Cu")
		(net 36)
	)
	(segment
		(start 137.516 115.692499)
		(end 137.527501 115.692499)
		(width 0.22)
		(layer "F.Cu")
		(net 36)
	)
	(segment
		(start 142.315 126.061655)
		(end 141.990001 125.736655)
		(width 0.22)
		(layer "F.Cu")
		(net 36)
	)
	(segment
		(start 140.618758 119.334)
		(end 137.718758 119.334)
		(width 0.22)
		(layer "F.Cu")
		(net 36)
	)
	(segment
		(start 142.315 127.99)
		(end 142.315 126.061655)
		(width 0.22)
		(layer "F.Cu")
		(net 36)
	)
	(via
		(at 137.71 115.51)
		(size 0.5)
		(drill 0.2)
		(layers "F.Cu" "B.Cu")
		(remove_unused_layers yes)
		(keep_end_layers yes)
		(zone_layer_connections)
		(net 36)
	)
	(segment
		(start 146.201414 92.74)
		(end 146.21 92.74)
		(width 0.22)
		(layer "B.Cu")
		(net 36)
	)
	(segment
		(start 137.515251 114.85)
		(end 137.515251 115.315251)
		(width 0.22)
		(layer "B.Cu")
		(net 36)
	)
	(segment
		(start 138.321 95.518)
		(end 138.321 106.360931)
		(width 0.22)
		(layer "B.Cu")
		(net 36)
	)
	(segment
		(start 146.21 92.593346)
		(end 145.868653 92.251999)
		(width 0.22)
		(layer "B.Cu")
		(net 36)
	)
	(segment
		(start 137.515251 115.315251)
		(end 137.71 115.51)
		(width 0.22)
		(layer "B.Cu")
		(net 36)
	)
	(segment
		(start 145.62 94.7)
		(end 145.45 94.53)
		(width 0.22)
		(layer "B.Cu")
		(net 36)
	)
	(segment
		(start 145.93 94.7)
		(end 145.62 94.7)
		(width 0.22)
		(layer "B.Cu")
		(net 36)
	)
	(segment
		(start 139.398001 92.251999)
		(end 138.321 93.329)
		(width 0.22)
		(layer "B.Cu")
		(net 36)
	)
	(segment
		(start 138.743529 95.008)
		(end 138.743529 95.11)
		(width 0.22)
		(layer "B.Cu")
		(net 36)
	)
	(segment
		(start 138.539529 95.314)
		(end 138.525 95.314)
		(width 0.22)
		(layer "B.Cu")
		(net 36)
	)
	(segment
		(start 138.525 94.804)
		(end 138.539529 94.804)
		(width 0.22)
		(layer "B.Cu")
		(net 36)
	)
	(segment
		(start 137.515 107.5)
		(end 137.517501 107.502501)
		(width 0.22)
		(layer "B.Cu")
		(net 36)
	)
	(segment
		(start 146.21 92.74)
		(end 146.21 92.593346)
		(width 0.22)
		(layer "B.Cu")
		(net 36)
	)
	(segment
		(start 137.517501 107.502501)
		(end 137.517501 114.84775)
		(width 0.22)
		(layer "B.Cu")
		(net 36)
	)
	(segment
		(start 145.45 93.491414)
		(end 146.201414 92.74)
		(width 0.22)
		(layer "B.Cu")
		(net 36)
	)
	(segment
		(start 145.868653 92.251999)
		(end 139.398001 92.251999)
		(width 0.22)
		(layer "B.Cu")
		(net 36)
	)
	(segment
		(start 138.321 94.498)
		(end 138.321 94.6)
		(width 0.22)
		(layer "B.Cu")
		(net 36)
	)
	(segment
		(start 138.743544 93.988)
		(end 138.743544 94.09)
		(width 0.22)
		(layer "B.Cu")
		(net 36)
	)
	(segment
		(start 138.321 106.360931)
		(end 138.28 106.401932)
		(width 0.22)
		(layer "B.Cu")
		(net 36)
	)
	(segment
		(start 138.539544 94.294)
		(end 138.525 94.294)
		(width 0.22)
		(layer "B.Cu")
		(net 36)
	)
	(segment
		(start 137.517501 114.84775)
		(end 137.515251 114.85)
		(width 0.22)
		(layer "B.Cu")
		(net 36)
	)
	(segment
		(start 145.45 94.53)
		(end 145.45 93.491414)
		(width 0.22)
		(layer "B.Cu")
		(net 36)
	)
	(segment
		(start 137.515 107.168346)
		(end 137.515 107.5)
		(width 0.22)
		(layer "B.Cu")
		(net 36)
	)
	(segment
		(start 138.28 106.401932)
		(end 138.28 106.403346)
		(width 0.22)
		(layer "B.Cu")
		(net 36)
	)
	(segment
		(start 138.28 106.403346)
		(end 137.515 107.168346)
		(width 0.22)
		(layer "B.Cu")
		(net 36)
	)
	(segment
		(start 138.525 93.784)
		(end 138.539544 93.784)
		(width 0.22)
		(layer "B.Cu")
		(net 36)
	)
	(segment
		(start 138.321 93.329)
		(end 138.321 93.58)
		(width 0.22)
		(layer "B.Cu")
		(net 36)
	)
	(arc
		(start 138.321 94.6)
		(mid 138.38075 94.74425)
		(end 138.525 94.804)
		(width 0.22)
		(layer "B.Cu")
		(net 36)
	)
	(arc
		(start 138.539529 94.804)
		(mid 138.683779 94.86375)
		(end 138.743529 95.008)
		(width 0.22)
		(layer "B.Cu")
		(net 36)
	)
	(arc
		(start 138.525 95.314)
		(mid 138.38075 95.37375)
		(end 138.321 95.518)
		(width 0.22)
		(layer "B.Cu")
		(net 36)
	)
	(arc
		(start 138.539544 93.784)
		(mid 138.683794 93.84375)
		(end 138.743544 93.988)
		(width 0.22)
		(layer "B.Cu")
		(net 36)
	)
	(arc
		(start 138.743529 95.11)
		(mid 138.683779 95.25425)
		(end 138.539529 95.314)
		(width 0.22)
		(layer "B.Cu")
		(net 36)
	)
	(arc
		(start 138.321 93.58)
		(mid 138.38075 93.72425)
		(end 138.525 93.784)
		(width 0.22)
		(layer "B.Cu")
		(net 36)
	)
	(arc
		(start 138.525 94.294)
		(mid 138.38075 94.35375)
		(end 138.321 94.498)
		(width 0.22)
		(layer "B.Cu")
		(net 36)
	)
	(arc
		(start 138.743544 94.09)
		(mid 138.683794 94.23425)
		(end 138.539544 94.294)
		(width 0.22)
		(layer "B.Cu")
		(net 36)
	)
	(segment
		(start 138.99 89.66)
		(end 137.15 91.5)
		(width 0.2)
		(layer "F.Cu")
		(net 37)
	)
	(segment
		(start 139.62 89.66)
		(end 138.99 89.66)
		(width 0.2)
		(layer "F.Cu")
		(net 37)
	)
	(segment
		(start 139.45 115.88)
		(end 139.45 102.7)
		(width 0.2)
		(layer "F.Cu")
		(net 37)
	)
	(segment
		(start 137.65 102.45)
		(end 137.35 102.75)
		(width 0.2)
		(layer "F.Cu")
		(net 37)
	)
	(segment
		(start 136.62 103.63)
		(end 136.92 103.63)
		(width 0.2)
		(layer "F.Cu")
		(net 37)
	)
	(segment
		(start 136.92 103.63)
		(end 137.35 103.2)
		(width 0.2)
		(layer "F.Cu")
		(net 37)
	)
	(segment
		(start 139.2 102.45)
		(end 137.65 102.45)
		(width 0.2)
		(layer "F.Cu")
		(net 37)
	)
	(segment
		(start 137.35 102.75)
		(end 137.35 103.2)
		(width 0.2)
		(layer "F.Cu")
		(net 37)
	)
	(segment
		(start 137.15 91.5)
		(end 137.15 100.12)
		(width 0.2)
		(layer "F.Cu")
		(net 37)
	)
	(segment
		(start 139.45 102.7)
		(end 139.2 102.45)
		(width 0.2)
		(layer "F.Cu")
		(net 37)
	)
	(segment
		(start 137.35 102.75)
		(end 137.6 102.5)
		(width 0.2)
		(layer "F.Cu")
		(net 37)
	)
	(via
		(at 137.15 100.12)
		(size 0.5)
		(drill 0.2)
		(layers "F.Cu" "B.Cu")
		(remove_unused_layers yes)
		(keep_end_layers yes)
		(zone_layer_connections)
		(teardrops
			(best_length_ratio 0.5)
			(max_length 1)
			(best_width_ratio 1)
			(max_width 2)
			(curved_edges yes)
			(filter_ratio 0.9)
			(enabled no)
			(allow_two_segments yes)
			(prefer_zone_connections yes)
		)
		(net 37)
	)
	(via
		(at 137.35 102.75)
		(size 0.5)
		(drill 0.2)
		(layers "F.Cu" "B.Cu")
		(remove_unused_layers yes)
		(keep_end_layers yes)
		(zone_layer_connections)
		(teardrops
			(best_length_ratio 0.5)
			(max_length 1)
			(best_width_ratio 1)
			(max_width 2)
			(curved_edges yes)
			(filter_ratio 0.9)
			(enabled no)
			(allow_two_segments yes)
			(prefer_zone_connections yes)
		)
		(net 37)
	)
	(via
		(at 139.45 115.88)
		(size 0.5)
		(drill 0.2)
		(layers "F.Cu" "B.Cu")
		(remove_unused_layers yes)
		(keep_end_layers yes)
		(zone_layer_connections)
		(teardrops
			(best_length_ratio 0.5)
			(max_length 1)
			(best_width_ratio 1)
			(max_width 2)
			(curved_edges yes)
			(filter_ratio 0.9)
			(enabled no)
			(allow_two_segments yes)
			(prefer_zone_connections yes)
		)
		(net 37)
	)
	(segment
		(start 137.76 118.29)
		(end 137.76 125.61)
		(width 0.2)
		(layer "B.Cu")
		(net 37)
	)
	(segment
		(start 139.45 116.6)
		(end 137.76 118.29)
		(width 0.2)
		(layer "B.Cu")
		(net 37)
	)
	(segment
		(start 137.35 102.75)
		(end 137.35 101.6)
		(width 0.2)
		(layer "B.Cu")
		(net 37)
	)
	(segment
		(start 137.35 101.6)
		(end 137.15 101.4)
		(width 0.2)
		(layer "B.Cu")
		(net 37)
	)
	(segment
		(start 141.411459 126.4)
		(end 142.145243 127.133784)
		(width 0.2)
		(layer "B.Cu")
		(net 37)
	)
	(segment
		(start 139.45 115.88)
		(end 139.45 116.6)
		(width 0.2)
		(layer "B.Cu")
		(net 37)
	)
	(segment
		(start 137.76 125.61)
		(end 138.55 126.4)
		(width 0.2)
		(layer "B.Cu")
		(net 37)
	)
	(segment
		(start 138.55 126.4)
		(end 141.411459 126.4)
		(width 0.2)
		(layer "B.Cu")
		(net 37)
	)
	(segment
		(start 137.15 101.4)
		(end 137.15 100.12)
		(width 0.2)
		(layer "B.Cu")
		(net 37)
	)
	(segment
		(start 142.145243 127.133784)
		(end 142.145243 128.9)
		(width 0.2)
		(layer "B.Cu")
		(net 37)
	)
	(segment
		(start 140.481654 119.665)
		(end 137.581654 119.665)
		(width 0.22)
		(layer "F.Cu")
		(net 38)
	)
	(segment
		(start 141.659001 120.842347)
		(end 140.481654 119.665)
		(width 0.22)
		(layer "F.Cu")
		(net 38)
	)
	(segment
		(start 137.185 115.68)
		(end 137.015 115.51)
		(width 0.22)
		(layer "F.Cu")
		(net 38)
	)
	(segment
		(start 137.581654 119.665)
		(end 137.185 119.268346)
		(width 0.22)
		(layer "F.Cu")
		(net 38)
	)
	(segment
		(start 141.984 126.198759)
		(end 141.659001 125.87376)
		(width 0.22)
		(layer "F.Cu")
		(net 38)
	)
	(segment
		(start 137.185 119.268346)
		(end 137.185 115.68)
		(width 0.22)
		(layer "F.Cu")
		(net 38)
	)
	(segment
		(start 141.984 127.991)
		(end 141.984 126.198759)
		(width 0.22)
		(layer "F.Cu")
		(net 38)
	)
	(segment
		(start 141.659001 125.87376)
		(end 141.659001 120.842347)
		(width 0.22)
		(layer "F.Cu")
		(net 38)
	)
	(via
		(at 137.015 115.51)
		(size 0.5)
		(drill 0.2)
		(layers "F.Cu" "B.Cu")
		(remove_unused_layers yes)
		(keep_end_layers yes)
		(zone_layer_connections)
		(net 38)
	)
	(segment
		(start 146.87 94.69)
		(end 147.1 94.69)
		(width 0.22)
		(layer "B.Cu")
		(net 38)
	)
	(segment
		(start 137.99 106.223827)
		(end 137.183 107.030827)
		(width 0.22)
		(layer "B.Cu")
		(net 38)
	)
	(segment
		(start 137.183 114.847749)
		(end 137.185251 114.85)
		(width 0.22)
		(layer "B.Cu")
		(net 38)
	)
	(segment
		(start 146.58 92.73)
		(end 146.57 92.73)
		(width 0.22)
		(layer "B.Cu")
		(net 38)
	)
	(segment
		(start 146.003346 91.92)
		(end 139.260482 91.92)
		(width 0.22)
		(layer "B.Cu")
		(net 38)
	)
	(segment
		(start 137.99 93.190482)
		(end 137.99 106.223827)
		(width 0.22)
		(layer "B.Cu")
		(net 38)
	)
	(segment
		(start 146.57 92.73)
		(end 146.57 92.486654)
		(width 0.22)
		(layer "B.Cu")
		(net 38)
	)
	(segment
		(start 147.252864 93.402864)
		(end 146.58 92.73)
		(width 0.22)
		(layer "B.Cu")
		(net 38)
	)
	(segment
		(start 137.185251 114.85)
		(end 137.185251 115.339749)
		(width 0.22)
		(layer "B.Cu")
		(net 38)
	)
	(segment
		(start 139.260482 91.92)
		(end 137.99 93.190482)
		(width 0.22)
		(layer "B.Cu")
		(net 38)
	)
	(segment
		(start 146.57 92.486654)
		(end 146.003346 91.92)
		(width 0.22)
		(layer "B.Cu")
		(net 38)
	)
	(segment
		(start 137.185251 115.339749)
		(end 137.015 115.51)
		(width 0.22)
		(layer "B.Cu")
		(net 38)
	)
	(segment
		(start 147.26 94.53)
		(end 147.26 93.402864)
		(width 0.22)
		(layer "B.Cu")
		(net 38)
	)
	(segment
		(start 137.183 107.030827)
		(end 137.183 114.847749)
		(width 0.22)
		(layer "B.Cu")
		(net 38)
	)
	(segment
		(start 147.26 93.402864)
		(end 147.252864 93.402864)
		(width 0.22)
		(layer "B.Cu")
		(net 38)
	)
	(segment
		(start 147.1 94.69)
		(end 147.26 94.53)
		(width 0.22)
		(layer "B.Cu")
		(net 38)
	)
	(segment
		(start 138.43 124.9)
		(end 137.74 124.21)
		(width 0.2)
		(layer "F.Cu")
		(net 41)
	)
	(segment
		(start 138.44 124.9)
		(end 138.43 124.9)
		(width 0.2)
		(layer "F.Cu")
		(net 41)
	)
	(segment
		(start 137.57 121.54)
		(end 136.74 121.54)
		(width 0.2)
		(layer "F.Cu")
		(net 41)
	)
	(segment
		(start 137.74 124.21)
		(end 137.74 121.71)
		(width 0.2)
		(layer "F.Cu")
		(net 41)
	)
	(segment
		(start 137.74 121.71)
		(end 137.57 121.54)
		(width 0.2)
		(layer "F.Cu")
		(net 41)
	)
	(via
		(at 138.44 124.9)
		(size 0.5)
		(drill 0.2)
		(layers "F.Cu" "B.Cu")
		(remove_unused_layers yes)
		(keep_end_layers yes)
		(zone_layer_connections)
		(teardrops
			(best_length_ratio 0.5)
			(max_length 1)
			(best_width_ratio 1)
			(max_width 2)
			(curved_edges yes)
			(filter_ratio 0.9)
			(enabled no)
			(allow_two_segments yes)
			(prefer_zone_connections yes)
		)
		(net 41)
	)
	(segment
		(start 138.44 124.9)
		(end 139.43 125.89)
		(width 0.2)
		(layer "B.Cu")
		(net 41)
	)
	(segment
		(start 141.78 125.89)
		(end 142.645243 126.755243)
		(width 0.2)
		(layer "B.Cu")
		(net 41)
	)
	(segment
		(start 139.43 125.89)
		(end 141.78 125.89)
		(width 0.2)
		(layer "B.Cu")
		(net 41)
	)
	(segment
		(start 142.645243 126.755243)
		(end 142.645243 128.9)
		(width 0.2)
		(layer "B.Cu")
		(net 41)
	)
	(segment
		(start 140.767041 93.122959)
		(end 140.82 93.07)
		(width 0.2)
		(layer "F.Cu")
		(net 50)
	)
	(segment
		(start 140.82 91.34)
		(end 140.82 93.07)
		(width 0.3)
		(layer "F.Cu")
		(net 50)
	)
	(segment
		(start 150.3 91.01)
		(end 150.46 91.17)
		(width 0.3)
		(layer "F.Cu")
		(net 50)
	)
	(segment
		(start 153.11 91.49)
		(end 152.79 91.17)
		(width 0.3)
		(layer "F.Cu")
		(net 50)
	)
	(segment
		(start 150.3 90.93)
		(end 150.3 91.01)
		(width 0.3)
		(layer "F.Cu")
		(net 50)
	)
	(segment
		(start 140.767041 94.282904)
		(end 140.767041 93.122959)
		(width 0.2)
		(layer "F.Cu")
		(net 50)
	)
	(segment
		(start 150.46 91.17)
		(end 151.35 91.17)
		(width 0.3)
		(layer "F.Cu")
		(net 50)
	)
	(segment
		(start 140.9 91.26)
		(end 140.82 91.34)
		(width 0.3)
		(layer "F.Cu")
		(net 50)
	)
	(segment
		(start 152.79 91.17)
		(end 152.32 91.17)
		(width 0.3)
		(layer "F.Cu")
		(net 50)
	)
	(via
		(at 140.9 91.26)
		(size 0.5)
		(drill 0.2)
		(layers "F.Cu" "B.Cu")
		(remove_unused_layers yes)
		(keep_end_layers yes)
		(zone_layer_connections)
		(net 50)
	)
	(via
		(at 153.11 91.49)
		(size 0.5)
		(drill 0.2)
		(layers "F.Cu" "B.Cu")
		(remove_unused_layers yes)
		(keep_end_layers yes)
		(zone_layer_connections)
		(net 50)
	)
	(via
		(at 152.04 96.23)
		(size 0.5)
		(drill 0.2)
		(layers "F.Cu" "B.Cu")
		(remove_unused_layers yes)
		(keep_end_layers yes)
		(zone_layer_connections)
		(net 50)
	)
	(via
		(at 150.3 90.93)
		(size 0.5)
		(drill 0.2)
		(layers "F.Cu" "B.Cu")
		(remove_unused_layers yes)
		(keep_end_layers yes)
		(zone_layer_connections)
		(net 50)
	)
	(segment
		(start 148.34 84.63)
		(end 150.3 86.59)
		(width 0.3)
		(layer "B.Cu")
		(net 50)
	)
	(segment
		(start 143.76 84.63)
		(end 148.34 84.63)
		(width 0.3)
		(layer "B.Cu")
		(net 50)
	)
	(segment
		(start 150.3 86.59)
		(end 150.3 90.93)
		(width 0.3)
		(layer "B.Cu")
		(net 50)
	)
	(segment
		(start 141.62 86.77)
		(end 143.76 84.63)
		(width 0.3)
		(layer "B.Cu")
		(net 50)
	)
	(segment
		(start 153.78 96.23)
		(end 152.04 96.23)
		(width 0.3)
		(layer "B.Cu")
		(net 50)
	)
	(segment
		(start 154.12 95.89)
		(end 153.78 96.23)
		(width 0.3)
		(layer "B.Cu")
		(net 50)
	)
	(segment
		(start 154.12 92.5)
		(end 154.12 95.89)
		(width 0.3)
		(layer "B.Cu")
		(net 50)
	)
	(segment
		(start 140.9 91.26)
		(end 141.62 90.54)
		(width 0.3)
		(layer "B.Cu")
		(net 50)
	)
	(segment
		(start 141.62 90.54)
		(end 141.62 86.77)
		(width 0.3)
		(layer "B.Cu")
		(net 50)
	)
	(segment
		(start 153.11 91.49)
		(end 154.12 92.5)
		(width 0.3)
		(layer "B.Cu")
		(net 50)
	)
	(segment
		(start 145.06672 95.64328)
		(end 145.267041 95.442959)
		(width 0.25)
		(layer "F.Cu")
		(net 51)
	)
	(segment
		(start 145.267041 95.442959)
		(end 145.267041 94.282904)
		(width 0.25)
		(layer "F.Cu")
		(net 51)
	)
	(segment
		(start 144.237446 95.64328)
		(end 145.06672 95.64328)
		(width 0.25)
		(layer "F.Cu")
		(net 51)
	)
	(segment
		(start 144.228723 95.634557)
		(end 144.237446 95.64328)
		(width 0.25)
		(layer "F.Cu")
		(net 51)
	)
	(via
		(at 144.228723 95.634557)
		(size 0.5)
		(drill 0.2)
		(layers "F.Cu" "B.Cu")
		(remove_unused_layers yes)
		(keep_end_layers yes)
		(zone_layer_connections)
		(net 51)
	)
	(segment
		(start 144.228723 95.634557)
		(end 144.228723 95.078723)
		(width 0.25)
		(layer "B.Cu")
		(net 51)
	)
	(segment
		(start 146.82 92.95)
		(end 146.82 93.507255)
		(width 0.2)
		(layer "F.Cu")
		(net 54)
	)
	(segment
		(start 146.755002 93.597581)
		(end 146.755002 93.636008)
		(width 0.22)
		(layer "F.Cu")
		(net 54)
	)
	(segment
		(start 146.767041 93.648047)
		(end 146.767041 94.282904)
		(width 0.2)
		(layer "F.Cu")
		(net 54)
	)
	(segment
		(start 146.742338 93.584917)
		(end 146.755002 93.597581)
		(width 0.22)
		(layer "F.Cu")
		(net 54)
	)
	(segment
		(start 146.82 93.507255)
		(end 146.742338 93.584917)
		(width 0.2)
		(layer "F.Cu")
		(net 54)
	)
	(via
		(at 146.742338 93.584917)
		(size 0.5)
		(drill 0.2)
		(layers "F.Cu" "B.Cu")
		(remove_unused_layers yes)
		(keep_end_layers yes)
		(zone_layer_connections)
		(net 54)
	)
	(segment
		(start 146.64 93.67)
		(end 146.64 94.06)
		(width 0.22)
		(layer "B.Cu")
		(net 54)
	)
	(segment
		(start 146.742338 93.584917)
		(end 146.725083 93.584917)
		(width 0.22)
		(layer "B.Cu")
		(net 54)
	)
	(segment
		(start 146.725083 93.584917)
		(end 146.64 93.67)
		(width 0.22)
		(layer "B.Cu")
		(net 54)
	)
	(segment
		(start 144.45 92.15)
		(end 144.595 92.295)
		(width 0.2)
		(layer "F.Cu")
		(net 55)
	)
	(segment
		(start 140.2 115.51)
		(end 140.2 101.85)
		(width 0.2)
		(layer "F.Cu")
		(net 55)
	)
	(segment
		(start 144.75 92.14)
		(end 145.26 92.14)
		(width 0.2)
		(layer "F.Cu")
		(net 55)
	)
	(segment
		(start 141.916 90.594966)
		(end 141.916 91.674966)
		(width 0.2)
		(layer "F.Cu")
		(net 55)
	)
	(segment
		(start 139.75 101.4)
		(end 136.65 101.4)
		(width 0.2)
		(layer "F.Cu")
		(net 55)
	)
	(segment
		(start 144.75 92.14)
		(end 144.595 92.295)
		(width 0.2)
		(layer "F.Cu")
		(net 55)
	)
	(segment
		(start 136.65 101.4)
		(end 136.58 101.33)
		(width 0.2)
		(layer "F.Cu")
		(net 55)
	)
	(segment
		(start 136.58 97.45)
		(end 136.575 97.445)
		(width 0.2)
		(layer "F.Cu")
		(net 55)
	)
	(segment
		(start 144.873116 92.852443)
		(end 144.873116 92.573116)
		(width 0.2)
		(layer "F.Cu")
		(net 55)
	)
	(segment
		(start 145.26 92.14)
		(end 145.38 92.26)
		(width 0.2)
		(layer "F.Cu")
		(net 55)
	)
	(segment
		(start 136.575 90.875)
		(end 138.5 88.95)
		(width 0.2)
		(layer "F.Cu")
		(net 55)
	)
	(segment
		(start 143.744 91.964)
		(end 143.93 92.15)
		(width 0.2)
		(layer "F.Cu")
		(net 55)
	)
	(segment
		(start 140.2 101.85)
		(end 139.75 101.4)
		(width 0.2)
		(layer "F.Cu")
		(net 55)
	)
	(segment
		(start 143.93 92.15)
		(end 144.45 92.15)
		(width 0.2)
		(layer "F.Cu")
		(net 55)
	)
	(segment
		(start 144.873116 92.573116)
		(end 144.595 92.295)
		(width 0.2)
		(layer "F.Cu")
		(net 55)
	)
	(segment
		(start 141.916 91.674966)
		(end 142.205034 91.964)
		(width 0.2)
		(layer "F.Cu")
		(net 55)
	)
	(segment
		(start 142.205034 91.964)
		(end 143.744 91.964)
		(width 0.2)
		(layer "F.Cu")
		(net 55)
	)
	(segment
		(start 136.575 97.445)
		(end 136.575 90.875)
		(width 0.2)
		(layer "F.Cu")
		(net 55)
	)
	(segment
		(start 141.07 88.95)
		(end 141.466 89.346)
		(width 0.2)
		(layer "F.Cu")
		(net 55)
	)
	(segment
		(start 136.58 101.33)
		(end 136.58 97.45)
		(width 0.2)
		(layer "F.Cu")
		(net 55)
	)
	(segment
		(start 144.862874 92.862685)
		(end 144.873116 92.852443)
		(width 0.2)
		(layer "F.Cu")
		(net 55)
	)
	(segment
		(start 145.38 92.26)
		(end 146.03 92.26)
		(width 0.2)
		(layer "F.Cu")
		(net 55)
	)
	(segment
		(start 141.466 90.144966)
		(end 141.916 90.594966)
		(width 0.2)
		(layer "F.Cu")
		(net 55)
	)
	(segment
		(start 141.466 89.346)
		(end 141.466 90.144966)
		(width 0.2)
		(layer "F.Cu")
		(net 55)
	)
	(segment
		(start 138.5 88.95)
		(end 141.07 88.95)
		(width 0.2)
		(layer "F.Cu")
		(net 55)
	)
	(via
		(at 144.862874 92.862685)
		(size 0.5)
		(drill 0.2)
		(layers "F.Cu" "B.Cu")
		(remove_unused_layers yes)
		(keep_end_layers yes)
		(zone_layer_connections)
		(net 55)
	)
	(via
		(at 140.2 115.51)
		(size 0.5)
		(drill 0.2)
		(layers "F.Cu" "B.Cu")
		(remove_unused_layers yes)
		(keep_end_layers yes)
		(zone_layer_connections)
		(teardrops
			(best_length_ratio 0.5)
			(max_length 1)
			(best_width_ratio 1)
			(max_width 2)
			(curved_edges yes)
			(filter_ratio 0.9)
			(enabled no)
			(allow_two_segments yes)
			(prefer_zone_connections yes)
		)
		(net 55)
	)
	(segment
		(start 145.114 94.864)
		(end 145.29 95.04)
		(width 0.2)
		(layer "B.Cu")
		(net 55)
	)
	(segment
		(start 143.61 125.7)
		(end 143.61 126.74)
		(width 0.2)
		(layer "B.Cu")
		(net 55)
	)
	(segment
		(start 140.2 115.51)
		(end 140.2 116.91)
		(width 0.2)
		(layer "B.Cu")
		(net 55)
	)
	(segment
		(start 138.39 123.59)
		(end 140.2 125.4)
		(width 0.2)
		(layer "B.Cu")
		(net 55)
	)
	(segment
		(start 145.29 95.04)
		(end 145.29 95.34)
		(width 0.2)
		(layer "B.Cu")
		(net 55)
	)
	(segment
		(start 144.873116 92.872927)
		(end 144.873116 92.899222)
		(width 0.2)
		(layer "B.Cu")
		(net 55)
	)
	(segment
		(start 140.2 116.91)
		(end 138.39 118.72)
		(width 0.2)
		(layer "B.Cu")
		(net 55)
	)
	(segment
		(start 144.873116 92.899222)
		(end 145.114 93.140106)
		(width 0.2)
		(layer "B.Cu")
		(net 55)
	)
	(segment
		(start 138.39 118.72)
		(end 138.39 123.59)
		(width 0.2)
		(layer "B.Cu")
		(net 55)
	)
	(segment
		(start 143.61 126.74)
		(end 143.145243 127.204757)
		(width 0.2)
		(layer "B.Cu")
		(net 55)
	)
	(segment
		(start 140.2 125.4)
		(end 143.31 125.4)
		(width 0.2)
		(layer "B.Cu")
		(net 55)
	)
	(segment
		(start 143.31 125.4)
		(end 143.61 125.7)
		(width 0.2)
		(layer "B.Cu")
		(net 55)
	)
	(segment
		(start 145.114 93.140106)
		(end 145.114 94.864)
		(width 0.2)
		(layer "B.Cu")
		(net 55)
	)
	(segment
		(start 143.145243 127.204757)
		(end 143.145243 128.9)
		(width 0.2)
		(layer "B.Cu")
		(net 55)
	)
	(segment
		(start 144.862874 92.862685)
		(end 144.873116 92.872927)
		(width 0.2)
		(layer "B.Cu")
		(net 55)
	)
	(segment
		(start 136.71 124.67)
		(end 137.03 124.67)
		(width 0.4)
		(layer "F.Cu")
		(net 56)
	)
	(segment
		(start 139.56 125.59)
		(end 139.57 125.59)
		(width 0.4)
		(layer "F.Cu")
		(net 56)
	)
	(segment
		(start 155.11 123.3)
		(end 155.11 93.1)
		(width 0.6)
		(layer "F.Cu")
		(net 56)
	)
	(segment
		(start 139.08 126.07)
		(end 139.08 127.02)
		(width 0.4)
		(layer "F.Cu")
		(net 56)
	)
	(segment
		(start 137.03 124.67)
		(end 137.92 125.56)
		(width 0.4)
		(layer "F.Cu")
		(net 56)
	)
	(segment
		(start 155.11 93.1)
		(end 154.232904 92.222904)
		(width 0.6)
		(layer "F.Cu")
		(net 56)
	)
	(segment
		(start 139.57 125.13)
		(end 140.3 124.4)
		(width 0.4)
		(layer "F.Cu")
		(net 56)
	)
	(segment
		(start 138.57 125.56)
		(end 139.08 126.07)
		(width 0.4)
		(layer "F.Cu")
		(net 56)
	)
	(segment
		(start 137.92 125.56)
		(end 138.57 125.56)
		(width 0.4)
		(layer "F.Cu")
		(net 56)
	)
	(segment
		(start 139.08 126.07)
		(end 139.56 125.59)
		(width 0.4)
		(layer "F.Cu")
		(net 56)
	)
	(segment
		(start 139.57 125.59)
		(end 139.57 125.13)
		(width 0.4)
		(layer "F.Cu")
		(net 56)
	)
	(segment
		(start 154.232904 92.222904)
		(end 152.319541 92.222904)
		(width 0.6)
		(layer "F.Cu")
		(net 56)
	)
	(via
		(at 154.82 124.13)
		(size 0.5)
		(drill 0.2)
		(layers "F.Cu" "B.Cu")
		(remove_unused_layers yes)
		(keep_end_layers yes)
		(zone_layer_connections)
		(teardrops
			(best_length_ratio 0.5)
			(max_length 1)
			(best_width_ratio 1)
			(max_width 2)
			(curved_edges yes)
			(filter_ratio 0.9)
			(enabled no)
			(allow_two_segments yes)
			(prefer_zone_connections yes)
		)
		(net 56)
	)
	(via
		(at 154.81 123.58)
		(size 0.5)
		(drill 0.2)
		(layers "F.Cu" "B.Cu")
		(remove_unused_layers yes)
		(keep_end_layers yes)
		(zone_layer_connections)
		(teardrops
			(best_length_ratio 0.5)
			(max_length 1)
			(best_width_ratio 1)
			(max_width 2)
			(curved_edges yes)
			(filter_ratio 0.9)
			(enabled no)
			(allow_two_segments yes)
			(prefer_zone_connections yes)
		)
		(net 56)
	)
	(via
		(at 155.42 124.11)
		(size 0.5)
		(drill 0.2)
		(layers "F.Cu" "B.Cu")
		(remove_unused_layers yes)
		(keep_end_layers yes)
		(free yes)
		(zone_layer_connections)
		(net 56)
	)
	(via
		(at 139.08 127.02)
		(size 0.5)
		(drill 0.2)
		(layers "F.Cu" "B.Cu")
		(remove_unused_layers yes)
		(keep_end_layers yes)
		(zone_layer_connections)
		(teardrops
			(best_length_ratio 0.5)
			(max_length 1)
			(best_width_ratio 1)
			(max_width 2)
			(curved_edges yes)
			(filter_ratio 0.9)
			(enabled no)
			(allow_two_segments yes)
			(prefer_zone_connections yes)
		)
		(net 56)
	)
	(via
		(at 155.42 123.58)
		(size 0.5)
		(drill 0.2)
		(layers "F.Cu" "B.Cu")
		(remove_unused_layers yes)
		(keep_end_layers yes)
		(free yes)
		(zone_layer_connections)
		(net 56)
	)
	(via
		(at 140.3 124.4)
		(size 0.5)
		(drill 0.2)
		(layers "F.Cu" "B.Cu")
		(remove_unused_layers yes)
		(keep_end_layers yes)
		(zone_layer_connections)
		(teardrops
			(best_length_ratio 0.5)
			(max_length 1)
			(best_width_ratio 1)
			(max_width 2)
			(curved_edges yes)
			(filter_ratio 0.9)
			(enabled no)
			(allow_two_segments yes)
			(prefer_zone_connections yes)
		)
		(net 56)
	)
	(segment
		(start 154.58 126.4)
		(end 152.95 126.4)
		(width 0.35)
		(layer "B.Cu")
		(net 56)
	)
	(segment
		(start 151.65 127.05)
		(end 151.65 128.895243)
		(width 0.35)
		(layer "B.Cu")
		(net 56)
	)
	(segment
		(start 154.8 126.4)
		(end 154.58 126.4)
		(width 0.35)
		(layer "B.Cu")
		(net 56)
	)
	(segment
		(start 155.08 124.14)
		(end 155.08 124.74)
		(width 0.4)
		(layer "B.Cu")
		(net 56)
	)
	(segment
		(start 137.645243 127.121243)
		(end 137.645243 128.9)
		(width 0.35)
		(layer "B.Cu")
		(net 56)
	)
	(segment
		(start 152.95 126.4)
		(end 152.65 126.7)
		(width 0.35)
		(layer "B.Cu")
		(net 56)
	)
	(segment
		(start 152.15 127.05)
		(end 152.65 127.05)
		(width 0.35)
		(layer "B.Cu")
		(net 56)
	)
	(segment
		(start 144.65 126.15)
		(end 144.65 124.6)
		(width 0.35)
		(layer "B.Cu")
		(net 56)
	)
	(segment
		(start 151.2 127.05)
		(end 151.65 127.05)
		(width 0.35)
		(layer "B.Cu")
		(net 56)
	)
	(segment
		(start 138.218243 127.05)
		(end 138.145243 127.123)
		(width 0.35)
		(layer "B.Cu")
		(net 56)
	)
	(segment
		(start 148.4 126.4)
		(end 144.9 126.4)
		(width 0.35)
		(layer "B.Cu")
		(net 56)
	)
	(segment
		(start 137.6 127.076)
		(end 137.645243 127.121243)
		(width 0.35)
		(layer "B.Cu")
		(net 56)
	)
	(segment
		(start 154.645243 128.9)
		(end 154.645243 126.465243)
		(width 0.35)
		(layer "B.Cu")
		(net 56)
	)
	(segment
		(start 138.218243 127.05)
		(end 138.192243 127.076)
		(width 0.35)
		(layer "B.Cu")
		(net 56)
	)
	(segment
		(start 149 125.8)
		(end 148.4 126.4)
		(width 0.35)
		(layer "B.Cu")
		(net 56)
	)
	(segment
		(start 144.45 124.4)
		(end 140.3 124.4)
		(width 0.35)
		(layer "B.Cu")
		(net 56)
	)
	(segment
		(start 151.145243 128.9)
		(end 151.145243 127.104757)
		(width 0.35)
		(layer "B.Cu")
		(net 56)
	)
	(segment
		(start 137.15 127.076)
		(end 137.15 128.895243)
		(width 0.35)
		(layer "B.Cu")
		(net 56)
	)
	(segment
		(start 151.2 127.05)
		(end 151.2 125.95)
		(width 0.35)
		(layer "B.Cu")
		(net 56)
	)
	(segment
		(start 152.65 127.05)
		(end 152.65 128.895243)
		(width 0.35)
		(layer "B.Cu")
		(net 56)
	)
	(segment
		(start 155.58 123.74)
		(end 155.42 123.58)
		(width 0.4)
		(layer "B.Cu")
		(net 56)
	)
	(segment
		(start 152.65 128.895243)
		(end 152.645243 128.9)
		(width 0.35)
		(layer "B.Cu")
		(net 56)
	)
	(segment
		(start 151.145243 127.104757)
		(end 151.2 127.05)
		(width 0.35)
		(layer "B.Cu")
		(net 56)
	)
	(segment
		(start 138.192243 127.076)
		(end 137.6 127.076)
		(width 0.35)
		(layer "B.Cu")
		(net 56)
	)
	(segment
		(start 144.65 124.6)
		(end 144.45 124.4)
		(width 0.35)
		(layer "B.Cu")
		(net 56)
	)
	(segment
		(start 152.31 90.09)
		(end 153.66 90.09)
		(width 0.6)
		(layer "B.Cu")
		(net 56)
	)
	(segment
		(start 154.645243 126.465243)
		(end 154.58 126.4)
		(width 0.35)
		(layer "B.Cu")
		(net 56)
	)
	(segment
		(start 153.66 90.09)
		(end 155.11 91.54)
		(width 0.6)
		(layer "B.Cu")
		(net 56)
	)
	(segment
		(start 152.15 128.895243)
		(end 152.145243 128.9)
		(width 0.35)
		(layer "B.Cu")
		(net 56)
	)
	(segment
		(start 137.6 127.076)
		(end 137.15 127.076)
		(width 0.35)
		(layer "B.Cu")
		(net 56)
	)
	(segment
		(start 144.9 126.4)
		(end 144.65 126.15)
		(width 0.35)
		(layer "B.Cu")
		(net 56)
	)
	(segment
		(start 152.65 126.7)
		(end 152.65 127.05)
		(width 0.35)
		(layer "B.Cu")
		(net 56)
	)
	(segment
		(start 156.29 123.74)
		(end 155.58 123.74)
		(width 0.4)
		(layer "B.Cu")
		(net 56)
	)
	(segment
		(start 154.65 125.17)
		(end 154.65 126.460486)
		(width 0.4)
		(layer "B.Cu")
		(net 56)
	)
	(segment
		(start 151.05 125.8)
		(end 149 125.8)
		(width 0.35)
		(layer "B.Cu")
		(net 56)
	)
	(segment
		(start 155.11 91.54)
		(end 155.11 123.68)
		(width 0.6)
		(layer "B.Cu")
		(net 56)
	)
	(segment
		(start 151.2 125.95)
		(end 151.05 125.8)
		(width 0.35)
		(layer "B.Cu")
		(net 56)
	)
	(segment
		(start 152.15 127.05)
		(end 152.15 128.895243)
		(width 0.35)
		(layer "B.Cu")
		(net 56)
	)
	(segment
		(start 138.145243 127.123)
		(end 138.145243 128.9)
		(width 0.35)
		(layer "B.Cu")
		(net 56)
	)
	(segment
		(start 155.145243 126.415243)
		(end 155.13 126.4)
		(width 0.35)
		(layer "B.Cu")
		(net 56)
	)
	(segment
		(start 139.05 127.05)
		(end 138.218243 127.05)
		(width 0.35)
		(layer "B.Cu")
		(net 56)
	)
	(segment
		(start 155.08 124.74)
		(end 154.65 125.17)
		(width 0.4)
		(layer "B.Cu")
		(net 56)
	)
	(segment
		(start 155.145243 128.9)
		(end 155.145243 126.415243)
		(width 0.35)
		(layer "B.Cu")
		(net 56)
	)
	(segment
		(start 151.65 128.895243)
		(end 151.645243 128.9)
		(width 0.35)
		(layer "B.Cu")
		(net 56)
	)
	(segment
		(start 154.65 126.460486)
		(end 154.645243 126.465243)
		(width 0.4)
		(layer "B.Cu")
		(net 56)
	)
	(segment
		(start 151.65 127.05)
		(end 152.15 127.05)
		(width 0.35)
		(layer "B.Cu")
		(net 56)
	)
	(segment
		(start 139.08 127.02)
		(end 139.05 127.05)
		(width 0.35)
		(layer "B.Cu")
		(net 56)
	)
	(segment
		(start 154.8 126.4)
		(end 155.13 126.4)
		(width 0.35)
		(layer "B.Cu")
		(net 56)
	)
	(segment
		(start 151.359541 94.05)
		(end 151.359541 92.222904)
		(width 0.4)
		(layer "F.Cu")
		(net 57)
	)
	(via
		(at 151.359541 94.05)
		(size 0.5)
		(drill 0.2)
		(layers "F.Cu" "B.Cu")
		(remove_unused_layers yes)
		(keep_end_layers yes)
		(zone_layer_connections)
		(net 57)
	)
	(segment
		(start 151.47 94.61)
		(end 151.39 94.53)
		(width 0.4)
		(layer "B.Cu")
		(net 57)
	)
	(segment
		(start 151.39 94.080459)
		(end 151.359541 94.05)
		(width 0.4)
		(layer "B.Cu")
		(net 57)
	)
	(segment
		(start 151.39 94.53)
		(end 151.39 94.080459)
		(width 0.4)
		(layer "B.Cu")
		(net 57)
	)
	(segment
		(start 146.82 92.31)
		(end 147.88 92.31)
		(width 0.2)
		(layer "F.Cu")
		(net 58)
	)
	(segment
		(start 149.35 90.84)
		(end 147.88 92.31)
		(width 0.2)
		(layer "F.Cu")
		(net 58)
	)
	(zone
		(net 1)
		(net_name "GND")
		(layer "F.Cu")
		(hatch edge 0.5)
		(priority 1)
		(connect_pads yes
			(clearance 0.2)
		)
		(min_thickness 0.25)
		(filled_areas_thickness no)
		(fill yes
			(thermal_gap 0.5)
			(thermal_bridge_width 0.5)
			(smoothing chamfer)
			(radius 0.2)
		)
		(polygon
			(pts
				(xy 138.27 126.92) (xy 138.27 126.099395) (xy 136.450487 126.089397) (xy 136.46074 126.92)
			)
		)
	)
	(zone
		(net 17)
		(net_name "+3V3")
		(layer "F.Cu")
		(hatch edge 0.5)
		(priority 3)
		(connect_pads yes
			(clearance 0.2)
		)
		(min_thickness 0.1)
		(filled_areas_thickness no)
		(fill yes
			(thermal_gap 0.5)
			(thermal_bridge_width 0.5)
			(smoothing chamfer)
			(radius 0.1)
		)
		(polygon
			(pts
				(xy 140.3 95.901031) (xy 141.4 95.901031) (xy 141.4 96.95) (xy 140.6 96.95) (xy 140.6 96.7) (xy 139.45 96.7)
				(xy 139.45 95.898527)
			)
		)
	)
	(zone
		(net 1)
		(net_name "GND")
		(layer "F.Cu")
		(hatch edge 0.5)
		(priority 4)
		(connect_pads yes
			(clearance 0.2)
		)
		(min_thickness 0.1)
		(filled_areas_thickness no)
		(fill yes
			(thermal_gap 0.5)
			(thermal_bridge_width 0.5)
			(smoothing chamfer)
			(radius 0.2)
		)
		(polygon
			(pts
				(xy 154.72 125.4) (xy 154.72 126.21) (xy 156.72 126.21) (xy 156.72 125.42)
			)
		)
	)
	(zone
		(net 57)
		(net_name "Net-(J2-V_{ACT}_TX_3V3)")
		(layer "F.Cu")
		(hatch edge 0.5)
		(priority 3)
		(connect_pads yes
			(clearance 0.2)
		)
		(min_thickness 0.1)
		(filled_areas_thickness no)
		(fill yes
			(thermal_gap 0.5)
			(thermal_bridge_width 0.5)
			(smoothing chamfer)
			(radius 0.2)
		)
		(polygon
			(pts
				(xy 150.550242 94.758948) (xy 150.550242 93.82) (xy 151.820242 93.82) (xy 151.820242 94.759474)
			)
		)
	)
	(zone
		(net 50)
		(net_name "Net-(J2-5V-PadA21)")
		(layer "F.Cu")
		(hatch edge 0.5)
		(priority 8)
		(connect_pads yes
			(clearance 0.2)
		)
		(min_thickness 0.1)
		(filled_areas_thickness no)
		(fill yes
			(thermal_gap 0.5)
			(thermal_bridge_width 0.5)
			(smoothing chamfer)
			(radius 0.1)
		)
		(polygon
			(pts
				(xy 151 96.015) (xy 152.27 96.015) (xy 152.28 96.63) (xy 151.45 96.63) (xy 151 96.63)
			)
		)
	)
	(zone
		(net 1)
		(net_name "GND")
		(layers "F.Cu" "B.Cu")
		(hatch edge 0.5)
		(priority 7)
		(connect_pads
			(clearance 0.2)
		)
		(min_thickness 0.25)
		(filled_areas_thickness no)
		(fill yes
			(thermal_gap 0.5)
			(thermal_bridge_width 0.5)
		)
		(polygon
			(pts
				(xy 147.97 50.8) (xy 148.92 50.8) (xy 148.83 51.35) (xy 148.63 51.9) (xy 148.43 52.23) (xy 148.08 52.65)
				(xy 147.74 52.93) (xy 147.28 53.22) (xy 146.83 53.39) (xy 146.56 53.46) (xy 146.29 53.5) (xy 146.02 53.51)
				(xy 145.76 53.5) (xy 145.47 53.46) (xy 145.2 53.39) (xy 144.66 53.17) (xy 144.41 53.02) (xy 144.04 52.73)
				(xy 143.72 52.38) (xy 143.49 52.04) (xy 143.3 51.64) (xy 143.21 51.35) (xy 143.14 51.07) (xy 143.12 50.8)
				(xy 144.07 50.8) (xy 144.14 51.16) (xy 144.3 51.54) (xy 144.61 51.97) (xy 145.02 52.28) (xy 145.43 52.47)
				(xy 145.64 52.52) (xy 145.96 52.55) (xy 146.18 52.55) (xy 146.4 52.52) (xy 146.58 52.48) (xy 146.77 52.41)
				(xy 146.94 52.33) (xy 147.12 52.23) (xy 147.41 51.98) (xy 147.56 51.81) (xy 147.78 51.46) (xy 147.91 51.12)
				(xy 147.95 50.97)
			)
		)
	)
	(zone
		(net 17)
		(net_name "+3V3")
		(layers "F.Cu" "B.Cu")
		(hatch edge 0.5)
		(priority 5)
		(connect_pads yes
			(clearance 0.2)
		)
		(min_thickness 0.25)
		(filled_areas_thickness no)
		(fill yes
			(thermal_gap 0.5)
			(thermal_bridge_width 0.5)
			(smoothing chamfer)
			(radius 0.1)
		)
		(polygon
			(pts
				(xy 139.73 90.31) (xy 139.73 91.48) (xy 140.38 91.48) (xy 140.37 90.31)
			)
		)
	)
	(zone
		(net 56)
		(net_name "Net-(C1-Pad2)")
		(layers "F.Cu" "B.Cu")
		(hatch edge 0.5)
		(priority 6)
		(connect_pads yes
			(clearance 0.2)
		)
		(min_thickness 0.25)
		(filled_areas_thickness no)
		(fill yes
			(thermal_gap 0.5)
			(thermal_bridge_width 0.5)
			(smoothing chamfer)
			(radius 0.2)
		)
		(polygon
			(pts
				(xy 155.72 123.28) (xy 154.47 123.28) (xy 154.47 124.38) (xy 155.73 124.38)
			)
		)
	)
	(zone
		(net 17)
		(net_name "+3V3")
		(layers "F.Cu" "B.Cu")
		(hatch edge 0.5)
		(priority 5)
		(connect_pads yes
			(clearance 0.2)
		)
		(min_thickness 0.25)
		(filled_areas_thickness no)
		(fill yes
			(thermal_gap 0.5)
			(thermal_bridge_width 0.5)
			(smoothing chamfer)
			(radius 0.1)
		)
		(polygon
			(pts
				(xy 139.75 92.73) (xy 139.75 93.9) (xy 140.4 93.9) (xy 140.39 92.73)
			)
		)
	)
	(zone
		(net 0)
		(net_name "")
		(layer "F.Mask")
		(hatch edge 0.5)
		(connect_pads
			(clearance 0.2)
		)
		(min_thickness 0.25)
		(filled_areas_thickness no)
		(fill yes
			(thermal_gap 0.5)
			(thermal_bridge_width 0.5)
		)
		(polygon
			(pts
				(xy 147.97 50.8) (xy 148.92 50.8) (xy 148.83 51.35) (xy 148.63 51.9) (xy 148.43 52.23) (xy 148.08 52.65)
				(xy 147.74 52.93) (xy 147.28 53.22) (xy 146.83 53.39) (xy 146.56 53.46) (xy 146.29 53.5) (xy 146.02 53.51)
				(xy 145.76 53.5) (xy 145.47 53.46) (xy 145.2 53.39) (xy 144.66 53.17) (xy 144.41 53.02) (xy 144.04 52.73)
				(xy 143.72 52.38) (xy 143.49 52.04) (xy 143.3 51.64) (xy 143.21 51.35) (xy 143.14 51.07) (xy 143.12 50.8)
				(xy 144.07 50.8) (xy 144.14 51.16) (xy 144.3 51.54) (xy 144.61 51.97) (xy 145.02 52.28) (xy 145.43 52.47)
				(xy 145.64 52.52) (xy 145.96 52.55) (xy 146.18 52.55) (xy 146.4 52.52) (xy 146.58 52.48) (xy 146.77 52.41)
				(xy 146.94 52.33) (xy 147.12 52.23) (xy 147.41 51.98) (xy 147.56 51.81) (xy 147.78 51.46) (xy 147.91 51.12)
				(xy 147.95 50.97)
			)
		)
	)
	(zone
		(net 0)
		(net_name "")
		(layer "F.Mask")
		(hatch edge 0.5)
		(connect_pads
			(clearance 0.2)
		)
		(min_thickness 0)
		(filled_areas_thickness no)
		(fill yes
			(thermal_gap 0.5)
			(thermal_bridge_width 0.5)
		)
		(polygon
			(pts
				(xy 136.16 127.881961) (xy 156.176876 127.900992) (xy 156.16 130.609517) (xy 136.16 130.699517)
			)
		)
	)
	(zone
		(net 0)
		(net_name "")
		(layer "B.Mask")
		(hatch edge 0.5)
		(connect_pads
			(clearance 0.2)
		)
		(min_thickness 0.25)
		(filled_areas_thickness no)
		(fill yes
			(thermal_gap 0.5)
			(thermal_bridge_width 0.5)
		)
		(polygon
			(pts
				(xy 147.97 50.8) (xy 148.92 50.8) (xy 148.83 51.35) (xy 148.63 51.9) (xy 148.43 52.23) (xy 148.08 52.65)
				(xy 147.74 52.93) (xy 147.28 53.22) (xy 146.83 53.39) (xy 146.56 53.46) (xy 146.29 53.5) (xy 146.02 53.51)
				(xy 145.76 53.5) (xy 145.47 53.46) (xy 145.2 53.39) (xy 144.66 53.17) (xy 144.41 53.02) (xy 144.04 52.73)
				(xy 143.72 52.38) (xy 143.49 52.04) (xy 143.3 51.64) (xy 143.21 51.35) (xy 143.14 51.07) (xy 143.12 50.8)
				(xy 144.07 50.8) (xy 144.14 51.16) (xy 144.3 51.54) (xy 144.61 51.97) (xy 145.02 52.28) (xy 145.43 52.47)
				(xy 145.64 52.52) (xy 145.96 52.55) (xy 146.18 52.55) (xy 146.4 52.52) (xy 146.58 52.48) (xy 146.77 52.41)
				(xy 146.94 52.33) (xy 147.12 52.23) (xy 147.41 51.98) (xy 147.56 51.81) (xy 147.78 51.46) (xy 147.91 51.12)
				(xy 147.95 50.97)
			)
		)
	)
	(zone
		(net 0)
		(net_name "")
		(layer "B.Mask")
		(hatch edge 0.5)
		(connect_pads
			(clearance 0.2)
		)
		(min_thickness 0)
		(filled_areas_thickness no)
		(fill yes
			(thermal_gap 0.5)
			(thermal_bridge_width 0.5)
		)
		(polygon
			(pts
				(xy 136.158975 127.390487) (xy 156.178913 127.409521) (xy 156.158975 130.609511) (xy 136.158975 130.699511)
			)
		)
	)
	(zone
		(net 0)
		(net_name "")
		(layers "In1.Cu" "In2.Cu")
		(name "Viagnd keepout")
		(hatch edge 0.5)
		(connect_pads
			(clearance 0)
		)
		(min_thickness 0.25)
		(filled_areas_thickness no)
		(keepout
			(tracks allowed)
			(vias allowed)
			(pads allowed)
			(copperpour not_allowed)
			(footprints allowed)
		)
		(placement
			(enabled no)
			(sheetname "")
		)
		(fill
			(thermal_gap 0.5)
			(thermal_bridge_width 0.5)
		)
		(polygon
			(pts
				(xy 152.33 124.94) (xy 152.98 124.94) (xy 152.98 125.54) (xy 152.33 125.54)
			)
		)
	)
	(zone
		(net 0)
		(net_name "")
		(layers "In1.Cu" "In2.Cu")
		(name "Viagnd keepout")
		(hatch edge 0.5)
		(connect_pads
			(clearance 0)
		)
		(min_thickness 0.25)
		(filled_areas_thickness no)
		(keepout
			(tracks allowed)
			(vias allowed)
			(pads allowed)
			(copperpour not_allowed)
			(footprints allowed)
		)
		(placement
			(enabled no)
			(sheetname "")
		)
		(fill
			(thermal_gap 0.5)
			(thermal_bridge_width 0.5)
		)
		(polygon
			(pts
				(xy 146.31 124.69) (xy 146.96 124.69) (xy 146.96 125.29) (xy 146.31 125.29)
			)
		)
	)
	(zone
		(net 0)
		(net_name "")
		(layers "In1.Cu" "In2.Cu")
		(name "Viagnd keepout")
		(hatch edge 0.5)
		(connect_pads
			(clearance 0)
		)
		(min_thickness 0.25)
		(filled_areas_thickness no)
		(keepout
			(tracks allowed)
			(vias allowed)
			(pads allowed)
			(copperpour not_allowed)
			(footprints allowed)
		)
		(placement
			(enabled no)
			(sheetname "")
		)
		(fill
			(thermal_gap 0.5)
			(thermal_bridge_width 0.5)
		)
		(polygon
			(pts
				(xy 147.68 94.88) (xy 148.33 94.88) (xy 148.33 95.48) (xy 147.68 95.48)
			)
		)
	)
	(zone
		(net 0)
		(net_name "")
		(layers "In1.Cu" "In2.Cu")
		(name "Viagnd keepout")
		(hatch edge 0.5)
		(connect_pads
			(clearance 0)
		)
		(min_thickness 0.25)
		(filled_areas_thickness no)
		(keepout
			(tracks allowed)
			(vias allowed)
			(pads allowed)
			(copperpour not_allowed)
			(footprints allowed)
		)
		(placement
			(enabled no)
			(sheetname "")
		)
		(fill
			(thermal_gap 0.5)
			(thermal_bridge_width 0.5)
		)
		(polygon
			(pts
				(xy 149.17 92.61) (xy 149.84 92.61) (xy 149.84 93.21) (xy 149.17 93.21)
			)
		)
	)
	(zone
		(net 0)
		(net_name "")
		(layers "In1.Cu" "In2.Cu")
		(name "Viagnd keepout")
		(hatch edge 0.5)
		(connect_pads
			(clearance 0)
		)
		(min_thickness 0.25)
		(filled_areas_thickness no)
		(keepout
			(tracks allowed)
			(vias allowed)
			(pads allowed)
			(copperpour not_allowed)
			(footprints allowed)
		)
		(placement
			(enabled no)
			(sheetname "")
		)
		(fill
			(thermal_gap 0.5)
			(thermal_bridge_width 0.5)
		)
		(polygon
			(pts
				(xy 149.34 123.06) (xy 149.99 123.06) (xy 149.99 123.66) (xy 149.34 123.66)
			)
		)
	)
	(zone
		(net 0)
		(net_name "")
		(layers "In1.Cu" "In2.Cu")
		(name "Viagnd keepout")
		(hatch edge 0.5)
		(connect_pads
			(clearance 0)
		)
		(min_thickness 0.25)
		(filled_areas_thickness no)
		(keepout
			(tracks allowed)
			(vias allowed)
			(pads allowed)
			(copperpour not_allowed)
			(footprints allowed)
		)
		(placement
			(enabled no)
			(sheetname "")
		)
		(fill
			(thermal_gap 0.5)
			(thermal_bridge_width 0.5)
		)
		(polygon
			(pts
				(xy 146.12 93.28) (xy 146.77 93.28) (xy 146.77 93.88) (xy 146.12 93.88)
			)
		)
	)
	(zone
		(net 0)
		(net_name "")
		(layers "In1.Cu" "In2.Cu")
		(name "Viagnd keepout")
		(hatch edge 0.5)
		(connect_pads
			(clearance 0)
		)
		(min_thickness 0.25)
		(filled_areas_thickness no)
		(keepout
			(tracks allowed)
			(vias allowed)
			(pads allowed)
			(copperpour not_allowed)
			(footprints allowed)
		)
		(placement
			(enabled no)
			(sheetname "")
		)
		(fill
			(thermal_gap 0.5)
			(thermal_bridge_width 0.5)
		)
		(polygon
			(pts
				(xy 141.66 94.78) (xy 142.42 94.78) (xy 142.42 95.38) (xy 141.66 95.38)
			)
		)
	)
	(zone
		(net 1)
		(net_name "GND")
		(layers "In1.Cu" "In2.Cu")
		(hatch edge 0.5)
		(connect_pads
			(clearance 0.2)
		)
		(min_thickness 0.2)
		(filled_areas_thickness no)
		(fill yes
			(thermal_gap 0.5)
			(thermal_bridge_width 0.5)
		)
		(polygon
			(pts
				(xy 115 50) (xy 179.5 50) (xy 179.5 136.5) (xy 116 136.5)
			)
		)
	)
	(zone
		(net 0)
		(net_name "")
		(layers "In1.Cu" "In2.Cu")
		(name "Viagnd keepout")
		(hatch edge 0.5)
		(connect_pads
			(clearance 0)
		)
		(min_thickness 0.25)
		(filled_areas_thickness no)
		(keepout
			(tracks allowed)
			(vias allowed)
			(pads allowed)
			(copperpour not_allowed)
			(footprints allowed)
		)
		(placement
			(enabled no)
			(sheetname "")
		)
		(fill
			(thermal_gap 0.5)
			(thermal_bridge_width 0.5)
		)
		(polygon
			(pts
				(xy 143.33 122.4) (xy 143.98 122.4) (xy 143.98 123) (xy 143.33 123)
			)
		)
	)
	(zone
		(net 0)
		(net_name "")
		(layers "In1.Cu" "In2.Cu")
		(name "Viagnd keepout")
		(hatch edge 0.5)
		(connect_pads
			(clearance 0)
		)
		(min_thickness 0.25)
		(filled_areas_thickness no)
		(keepout
			(tracks allowed)
			(vias allowed)
			(pads allowed)
			(copperpour not_allowed)
			(footprints allowed)
		)
		(placement
			(enabled no)
			(sheetname "")
		)
		(fill
			(thermal_gap 0.5)
			(thermal_bridge_width 0.5)
		)
		(polygon
			(pts
				(xy 143.2 92.91) (xy 143.85 92.91) (xy 143.85 93.51) (xy 143.2 93.51)
			)
		)
	)
	(zone
		(net 0)
		(net_name "")
		(layers "In1.Cu" "In2.Cu")
		(name "Viagnd keepout")
		(hatch edge 0.5)
		(connect_pads
			(clearance 0)
		)
		(min_thickness 0.25)
		(filled_areas_thickness no)
		(keepout
			(tracks allowed)
			(vias allowed)
			(pads allowed)
			(copperpour not_allowed)
			(footprints allowed)
		)
		(placement
			(enabled no)
			(sheetname "")
		)
		(fill
			(thermal_gap 0.5)
			(thermal_bridge_width 0.5)
		)
		(polygon
			(pts
				(xy 146.68 96.82) (xy 147.39 96.82) (xy 147.39 97.42) (xy 146.68 97.42)
			)
		)
	)
)
